FILE_TYPE=LIBRARY_PARTS;
primitive 'AST2520A1-GP-GP';
  pin
    'MDQ4':
      PIN_NUMBER='(U9,0,0,0,0,0,0)';
      BIDIRECTIONAL='TRUE';
      INPUT_LOAD='(-0.01,0.01)';
      OUTPUT_LOAD='(1.0,-1.0)';
    'MDQ3':
      PIN_NUMBER='(AA10,0,0,0,0,0,0)';
      BIDIRECTIONAL='TRUE';
      INPUT_LOAD='(-0.01,0.01)';
      OUTPUT_LOAD='(1.0,-1.0)';
    'MDQ2':
      PIN_NUMBER='(Y10,0,0,0,0,0,0)';
      BIDIRECTIONAL='TRUE';
      INPUT_LOAD='(-0.01,0.01)';
      OUTPUT_LOAD='(1.0,-1.0)';
    'MDQ1':
      PIN_NUMBER='(W10,0,0,0,0,0,0)';
      BIDIRECTIONAL='TRUE';
      INPUT_LOAD='(-0.01,0.01)';
      OUTPUT_LOAD='(1.0,-1.0)';
    'MDQ0':
      PIN_NUMBER='(U10,0,0,0,0,0,0)';
      BIDIRECTIONAL='TRUE';
      INPUT_LOAD='(-0.01,0.01)';
      OUTPUT_LOAD='(1.0,-1.0)';
    'MA15':
      PIN_NUMBER='(U15,0,0,0,0,0,0)';
      OUTPUT_LOAD='(1.0,-1.0)';
    'MDQ15':
      PIN_NUMBER='(U7,0,0,0,0,0,0)';
      BIDIRECTIONAL='TRUE';
      INPUT_LOAD='(-0.01,0.01)';
      OUTPUT_LOAD='(1.0,-1.0)';
    'MDQ14':
      PIN_NUMBER='(V7,0,0,0,0,0,0)';
      BIDIRECTIONAL='TRUE';
      INPUT_LOAD='(-0.01,0.01)';
      OUTPUT_LOAD='(1.0,-1.0)';
    'MDM1':
      PIN_NUMBER='(AB8,0,0,0,0,0,0)';
      OUTPUT_LOAD='(1.0,-1.0)';
    'MIOZ':
      PIN_NUMBER='(W11,0,0,0,0,0,0)';
      PIN_TYPE='ANALOG';
      NO_LOAD_CHECK='Both';
      NO_IO_CHECK='Both';
      NO_ASSERT_CHECK='TRUE';
      NO_DIR_CHECK='TRUE';
      ALLOW_CONNECT='TRUE';
    'MCAS#':
      PIN_NUMBER='(AB13,0,0,0,0,0,0)';
      OUTPUT_LOAD='(1.0,-1.0)';
    'MA10':
      PIN_NUMBER='(U13,0,0,0,0,0,0)';
      OUTPUT_LOAD='(1.0,-1.0)';
    'MA11':
      PIN_NUMBER='(AA14,0,0,0,0,0,0)';
      OUTPUT_LOAD='(1.0,-1.0)';
    'MVREF':
      PIN_NUMBER='(T9,0,0,0,0,0,0)';
      PIN_TYPE='ANALOG';
      NO_LOAD_CHECK='Both';
      NO_IO_CHECK='Both';
      NO_ASSERT_CHECK='TRUE';
      NO_DIR_CHECK='TRUE';
      ALLOW_CONNECT='TRUE';
    'MDQ9':
      PIN_NUMBER='(Y8,0,0,0,0,0,0)';
      BIDIRECTIONAL='TRUE';
      INPUT_LOAD='(-0.01,0.01)';
      OUTPUT_LOAD='(1.0,-1.0)';
    'MODT':
      PIN_NUMBER='(V11,0,0,0,0,0,0)';
      OUTPUT_LOAD='(1.0,-1.0)';
    'MCKE':
      PIN_NUMBER='(Y11,0,0,0,0,0,0)';
      OUTPUT_LOAD='(1.0,-1.0)';
    'MCKN':
      PIN_NUMBER='(AB12,0,0,0,0,0,0)';
      OUTPUT_LOAD='(1.0,-1.0)';
    'MBA2_MBG0':
      PIN_NUMBER='(W13,0,0,0,0,0,0)';
      OUTPUT_LOAD='(1.0,-1.0)';
    'MBA1':
      PIN_NUMBER='(Y13,0,0,0,0,0,0)';
      OUTPUT_LOAD='(1.0,-1.0)';
    'MBA0':
      PIN_NUMBER='(U12,0,0,0,0,0,0)';
      OUTPUT_LOAD='(1.0,-1.0)';
    'MA9':
      PIN_NUMBER='(Y16,0,0,0,0,0,0)';
      OUTPUT_LOAD='(1.0,-1.0)';
    'MA8':
      PIN_NUMBER='(W16,0,0,0,0,0,0)';
      OUTPUT_LOAD='(1.0,-1.0)';
    'MA7':
      PIN_NUMBER='(AA16,0,0,0,0,0,0)';
      OUTPUT_LOAD='(1.0,-1.0)';
    'MA6':
      PIN_NUMBER='(AB16,0,0,0,0,0,0)';
      OUTPUT_LOAD='(1.0,-1.0)';
    'MA5':
      PIN_NUMBER='(V15,0,0,0,0,0,0)';
      OUTPUT_LOAD='(1.0,-1.0)';
    'MA4':
      PIN_NUMBER='(W15,0,0,0,0,0,0)';
      OUTPUT_LOAD='(1.0,-1.0)';
    'MA3':
      PIN_NUMBER='(U14,0,0,0,0,0,0)';
      OUTPUT_LOAD='(1.0,-1.0)';
    'MA2':
      PIN_NUMBER='(W14,0,0,0,0,0,0)';
      OUTPUT_LOAD='(1.0,-1.0)';
    'MA12':
      PIN_NUMBER='(Y14,0,0,0,0,0,0)';
      OUTPUT_LOAD='(1.0,-1.0)';
    'MA1':
      PIN_NUMBER='(AB14,0,0,0,0,0,0)';
      OUTPUT_LOAD='(1.0,-1.0)';
    'MA0':
      PIN_NUMBER='(V13,0,0,0,0,0,0)';
      OUTPUT_LOAD='(1.0,-1.0)';
    'MDQS1P':
      PIN_NUMBER='(AB7,0,0,0,0,0,0)';
      BIDIRECTIONAL='TRUE';
      INPUT_LOAD='(-0.01,0.01)';
      OUTPUT_LOAD='(1.0,-1.0)';
    'MDQS1N':
      PIN_NUMBER='(AB6,0,0,0,0,0,0)';
      BIDIRECTIONAL='TRUE';
      INPUT_LOAD='(-0.01,0.01)';
      OUTPUT_LOAD='(1.0,-1.0)';
    'MDQS0P':
      PIN_NUMBER='(AB9,0,0,0,0,0,0)';
      BIDIRECTIONAL='TRUE';
      INPUT_LOAD='(-0.01,0.01)';
      OUTPUT_LOAD='(1.0,-1.0)';
    'MDQS0N':
      PIN_NUMBER='(AB10,0,0,0,0,0,0)';
      BIDIRECTIONAL='TRUE';
      INPUT_LOAD='(-0.01,0.01)';
      OUTPUT_LOAD='(1.0,-1.0)';
    'MDQ6':
      PIN_NUMBER='(W9,0,0,0,0,0,0)';
      BIDIRECTIONAL='TRUE';
      INPUT_LOAD='(-0.01,0.01)';
      OUTPUT_LOAD='(1.0,-1.0)';
    'MDQ5':
      PIN_NUMBER='(Y9,0,0,0,0,0,0)';
      BIDIRECTIONAL='TRUE';
      INPUT_LOAD='(-0.01,0.01)';
      OUTPUT_LOAD='(1.0,-1.0)';
    'MDQ13':
      PIN_NUMBER='(W7,0,0,0,0,0,0)';
      BIDIRECTIONAL='TRUE';
      INPUT_LOAD='(-0.01,0.01)';
      OUTPUT_LOAD='(1.0,-1.0)';
    'MDQ12':
      PIN_NUMBER='(AA6,0,0,0,0,0,0)';
      BIDIRECTIONAL='TRUE';
      INPUT_LOAD='(-0.01,0.01)';
      OUTPUT_LOAD='(1.0,-1.0)';
    'MDM0':
      PIN_NUMBER='(U8,0,0,0,0,0,0)';
      OUTPUT_LOAD='(1.0,-1.0)';
    'MA13':
      PIN_NUMBER='(AB15,0,0,0,0,0,0)';
      OUTPUT_LOAD='(1.0,-1.0)';
    'MA14_MACT#':
      PIN_NUMBER='(Y15,0,0,0,0,0,0)';
      OUTPUT_LOAD='(1.0,-1.0)';
    'MDQ11':
      PIN_NUMBER='(W8,0,0,0,0,0,0)';
      BIDIRECTIONAL='TRUE';
      INPUT_LOAD='(-0.01,0.01)';
      OUTPUT_LOAD='(1.0,-1.0)';
    'MDQ10':
      PIN_NUMBER='(Y7,0,0,0,0,0,0)';
      BIDIRECTIONAL='TRUE';
      INPUT_LOAD='(-0.01,0.01)';
      OUTPUT_LOAD='(1.0,-1.0)';
    'MWE#':
      PIN_NUMBER='(Y12,0,0,0,0,0,0)';
      OUTPUT_LOAD='(1.0,-1.0)';
    'MRAS#':
      PIN_NUMBER='(W12,0,0,0,0,0,0)';
      OUTPUT_LOAD='(1.0,-1.0)';
    'MDQ7':
      PIN_NUMBER='(V9,0,0,0,0,0,0)';
      BIDIRECTIONAL='TRUE';
      INPUT_LOAD='(-0.01,0.01)';
      OUTPUT_LOAD='(1.0,-1.0)';
    'MDQ8':
      PIN_NUMBER='(AA8,0,0,0,0,0,0)';
      BIDIRECTIONAL='TRUE';
      INPUT_LOAD='(-0.01,0.01)';
      OUTPUT_LOAD='(1.0,-1.0)';
    'MCKP':
      PIN_NUMBER='(AB11,0,0,0,0,0,0)';
      OUTPUT_LOAD='(1.0,-1.0)';
    'MCS#':
      PIN_NUMBER='(AA12,0,0,0,0,0,0)';
      OUTPUT_LOAD='(1.0,-1.0)';
    'GPIOB6_LPCPME#':
      PIN_NUMBER='(0,H22,0,0,0,0,0)';
      BIDIRECTIONAL='TRUE';
      INPUT_LOAD='(-0.01,0.01)';
      OUTPUT_LOAD='(1.0,-1.0)';
    'GPIOB4_USBCKI':
      PIN_NUMBER='(0,J20,0,0,0,0,0)';
      BIDIRECTIONAL='TRUE';
      INPUT_LOAD='(-0.01,0.01)';
      OUTPUT_LOAD='(1.0,-1.0)';
    'GPIOY4_SCL1':
      PIN_NUMBER='(0,M18,0,0,0,0,0)';
      BIDIRECTIONAL='TRUE';
      INPUT_LOAD='(-0.01,0.01)';
      OUTPUT_LOAD='(1.0,-1.0)';
    'GPIOI7_SPI1MISO_VBMISO':
      PIN_NUMBER='(0,A15,0,0,0,0,0)';
      BIDIRECTIONAL='TRUE';
      INPUT_LOAD='(-0.01,0.01)';
      OUTPUT_LOAD='(1.0,-1.0)';
    'DACRSET':
      PIN_NUMBER='(0,K4,0,0,0,0,0)';
      PIN_TYPE='ANALOG';
      NO_LOAD_CHECK='Both';
      NO_IO_CHECK='Both';
      NO_ASSERT_CHECK='TRUE';
      NO_DIR_CHECK='TRUE';
      ALLOW_CONNECT='TRUE';
    'DACR':
      PIN_NUMBER='(0,J4,0,0,0,0,0)';
      OUTPUT_LOAD='(1.0,-1.0)';
    'DACG':
      PIN_NUMBER='(0,J3,0,0,0,0,0)';
      OUTPUT_LOAD='(1.0,-1.0)';
    'TMS':
      PIN_NUMBER='(0,C8,0,0,0,0,0)';
      BIDIRECTIONAL='TRUE';
      INPUT_LOAD='(-0.01,0.01)';
      OUTPUT_LOAD='(1.0,-1.0)';
    'TDI':
      PIN_NUMBER='(0,D12,0,0,0,0,0)';
      BIDIRECTIONAL='TRUE';
      INPUT_LOAD='(-0.01,0.01)';
      OUTPUT_LOAD='(1.0,-1.0)';
    'TCK':
      PIN_NUMBER='(0,C10,0,0,0,0,0)';
      BIDIRECTIONAL='TRUE';
      INPUT_LOAD='(-0.01,0.01)';
      OUTPUT_LOAD='(1.0,-1.0)';
    'RTCK':
      PIN_NUMBER='(0,C9,0,0,0,0,0)';
      OUTPUT_LOAD='(1.0,-1.0)';
    'NTRST':
      PIN_NUMBER='(0,E11,0,0,0,0,0)';
      BIDIRECTIONAL='TRUE';
      INPUT_LOAD='(-0.01,0.01)';
      OUTPUT_LOAD='(1.0,-1.0)';
    'GPIOI1_SYSCK':
      PIN_NUMBER='(0,E15,0,0,0,0,0)';
      BIDIRECTIONAL='TRUE';
      INPUT_LOAD='(-0.01,0.01)';
      OUTPUT_LOAD='(1.0,-1.0)';
    'GPIOI0_SYSCS#':
      PIN_NUMBER='(0,C18,0,0,0,0,0)';
      BIDIRECTIONAL='TRUE';
      INPUT_LOAD='(-0.01,0.01)';
      OUTPUT_LOAD='(1.0,-1.0)';
    'GPIOI5_SPI1CK_VBCK':
      PIN_NUMBER='(0,C15,0,0,0,0,0)';
      BIDIRECTIONAL='TRUE';
      INPUT_LOAD='(-0.01,0.01)';
      OUTPUT_LOAD='(1.0,-1.0)';
    'GPIOI4_SPI1CS0#_VBCS#':
      PIN_NUMBER='(0,B15,0,0,0,0,0)';
      BIDIRECTIONAL='TRUE';
      INPUT_LOAD='(-0.01,0.01)';
      OUTPUT_LOAD='(1.0,-1.0)';
    'GPIOI6_SPI1MOSI_VBMOSI':
      PIN_NUMBER='(0,A14,0,0,0,0,0)';
      BIDIRECTIONAL='TRUE';
      INPUT_LOAD='(-0.01,0.01)';
      OUTPUT_LOAD='(1.0,-1.0)';
    'GPIOJ1_SGPMLD':
      PIN_NUMBER='(0,L2,0,0,0,0,0)';
      BIDIRECTIONAL='TRUE';
      INPUT_LOAD='(-0.01,0.01)';
      OUTPUT_LOAD='(1.0,-1.0)';
    'GPIOJ0_SGPMCK':
      PIN_NUMBER='(0,R2,0,0,0,0,0)';
      BIDIRECTIONAL='TRUE';
      INPUT_LOAD='(-0.01,0.01)';
      OUTPUT_LOAD='(1.0,-1.0)';
    'GPIOJ2_SGPMO':
      PIN_NUMBER='(0,N3,0,0,0,0,0)';
      BIDIRECTIONAL='TRUE';
      INPUT_LOAD='(-0.01,0.01)';
      OUTPUT_LOAD='(1.0,-1.0)';
    'GPIOG3_SGPS1I1':
      PIN_NUMBER='(0,E16,0,0,0,0,0)';
      BIDIRECTIONAL='TRUE';
      INPUT_LOAD='(-0.01,0.01)';
      OUTPUT_LOAD='(1.0,-1.0)';
    'GPIOG2_SGPS1I0':
      PIN_NUMBER='(0,C19,0,0,0,0,0)';
      BIDIRECTIONAL='TRUE';
      INPUT_LOAD='(-0.01,0.01)';
      OUTPUT_LOAD='(1.0,-1.0)';
    'DACB':
      PIN_NUMBER='(0,J2,0,0,0,0,0)';
      OUTPUT_LOAD='(1.0,-1.0)';
    'GPIOY5_SDA1':
      PIN_NUMBER='(0,M19,0,0,0,0,0)';
      BIDIRECTIONAL='TRUE';
      INPUT_LOAD='(-0.01,0.01)';
      OUTPUT_LOAD='(1.0,-1.0)';
    'TDO':
      PIN_NUMBER='(0,D11,0,0,0,0,0)';
      BIDIRECTIONAL='TRUE';
      INPUT_LOAD='(-0.01,0.01)';
      OUTPUT_LOAD='(1.0,-1.0)';
    'GPIOB0':
      PIN_NUMBER='(0,K19,0,0,0,0,0)';
      BIDIRECTIONAL='TRUE';
      INPUT_LOAD='(-0.01,0.01)';
      OUTPUT_LOAD='(1.0,-1.0)';
    'GPIOB1':
      PIN_NUMBER='(0,L19,0,0,0,0,0)';
      BIDIRECTIONAL='TRUE';
      INPUT_LOAD='(-0.01,0.01)';
      OUTPUT_LOAD='(1.0,-1.0)';
    'GPIOB2':
      PIN_NUMBER='(0,L18,0,0,0,0,0)';
      BIDIRECTIONAL='TRUE';
      INPUT_LOAD='(-0.01,0.01)';
      OUTPUT_LOAD='(1.0,-1.0)';
    'GPIOB3':
      PIN_NUMBER='(0,K18,0,0,0,0,0)';
      BIDIRECTIONAL='TRUE';
      INPUT_LOAD='(-0.01,0.01)';
      OUTPUT_LOAD='(1.0,-1.0)';
    'GPIOB7':
      PIN_NUMBER='(0,H20,0,0,0,0,0)';
      BIDIRECTIONAL='TRUE';
      INPUT_LOAD='(-0.01,0.01)';
      OUTPUT_LOAD='(1.0,-1.0)';
    'GPIOY6_SCL2':
      PIN_NUMBER='(0,M20,0,0,0,0,0)';
      BIDIRECTIONAL='TRUE';
      INPUT_LOAD='(-0.01,0.01)';
      OUTPUT_LOAD='(1.0,-1.0)';
    'GPIOY7_SDA2':
      PIN_NUMBER='(0,P20,0,0,0,0,0)';
      BIDIRECTIONAL='TRUE';
      INPUT_LOAD='(-0.01,0.01)';
      OUTPUT_LOAD='(1.0,-1.0)';
    'GPIOQ0_SCL3':
      PIN_NUMBER='(0,A11,0,0,0,0,0)';
      BIDIRECTIONAL='TRUE';
      INPUT_LOAD='(-0.01,0.01)';
      OUTPUT_LOAD='(1.0,-1.0)';
    'GPIOQ1_SDA3':
      PIN_NUMBER='(0,A10,0,0,0,0,0)';
      BIDIRECTIONAL='TRUE';
      INPUT_LOAD='(-0.01,0.01)';
      OUTPUT_LOAD='(1.0,-1.0)';
    'GPIOQ2_SCL4':
      PIN_NUMBER='(0,A9,0,0,0,0,0)';
      BIDIRECTIONAL='TRUE';
      INPUT_LOAD='(-0.01,0.01)';
      OUTPUT_LOAD='(1.0,-1.0)';
    'GPIOQ3_SDA4':
      PIN_NUMBER='(0,B9,0,0,0,0,0)';
      BIDIRECTIONAL='TRUE';
      INPUT_LOAD='(-0.01,0.01)';
      OUTPUT_LOAD='(1.0,-1.0)';
    'GPIOK0_SCL5':
      PIN_NUMBER='(0,L3,0,0,0,0,0)';
      BIDIRECTIONAL='TRUE';
      INPUT_LOAD='(-0.01,0.01)';
      OUTPUT_LOAD='(1.0,-1.0)';
    'GPIOK1_SDA5':
      PIN_NUMBER='(0,L4,0,0,0,0,0)';
      BIDIRECTIONAL='TRUE';
      INPUT_LOAD='(-0.01,0.01)';
      OUTPUT_LOAD='(1.0,-1.0)';
    'GPIOK2_SCL6':
      PIN_NUMBER='(0,L1,0,0,0,0,0)';
      BIDIRECTIONAL='TRUE';
      INPUT_LOAD='(-0.01,0.01)';
      OUTPUT_LOAD='(1.0,-1.0)';
    'GPIOK3_SDA6':
      PIN_NUMBER='(0,N2,0,0,0,0,0)';
      BIDIRECTIONAL='TRUE';
      INPUT_LOAD='(-0.01,0.01)';
      OUTPUT_LOAD='(1.0,-1.0)';
    'GPIOG1_SGPS1LD':
      PIN_NUMBER='(0,E19,0,0,0,0,0)';
      BIDIRECTIONAL='TRUE';
      INPUT_LOAD='(-0.01,0.01)';
      OUTPUT_LOAD='(1.0,-1.0)';
    'GPIOG0_SGPS1CK':
      PIN_NUMBER='(0,A19,0,0,0,0,0)';
      BIDIRECTIONAL='TRUE';
      INPUT_LOAD='(-0.01,0.01)';
      OUTPUT_LOAD='(1.0,-1.0)';
    'GPIOJ3_SGPMI':
      PIN_NUMBER='(0,N4,0,0,0,0,0)';
      BIDIRECTIONAL='TRUE';
      INPUT_LOAD='(-0.01,0.01)';
      OUTPUT_LOAD='(1.0,-1.0)';
    'GPIOI2_SYSMOSI':
      PIN_NUMBER='(0,B16,0,0,0,0,0)';
      BIDIRECTIONAL='TRUE';
      INPUT_LOAD='(-0.01,0.01)';
      OUTPUT_LOAD='(1.0,-1.0)';
    'GPIOI3_SYSMISO':
      PIN_NUMBER='(0,C16,0,0,0,0,0)';
      BIDIRECTIONAL='TRUE';
      INPUT_LOAD='(-0.01,0.01)';
      OUTPUT_LOAD='(1.0,-1.0)';
    'GPIOA5_TIMER6_SDA9':
      PIN_NUMBER='(0,A13,0,0,0,0,0)';
      BIDIRECTIONAL='TRUE';
      INPUT_LOAD='(-0.01,0.01)';
      OUTPUT_LOAD='(1.0,-1.0)';
    'GPIOA4_TIMER5_SCL9':
      PIN_NUMBER='(0,C14,0,0,0,0,0)';
      BIDIRECTIONAL='TRUE';
      INPUT_LOAD='(-0.01,0.01)';
      OUTPUT_LOAD='(1.0,-1.0)';
    'GPIOK7_SDA8':
      PIN_NUMBER='(0,R1,0,0,0,0,0)';
      BIDIRECTIONAL='TRUE';
      INPUT_LOAD='(-0.01,0.01)';
      OUTPUT_LOAD='(1.0,-1.0)';
    'GPIOK6_SCL8':
      PIN_NUMBER='(0,P2,0,0,0,0,0)';
      BIDIRECTIONAL='TRUE';
      INPUT_LOAD='(-0.01,0.01)';
      OUTPUT_LOAD='(1.0,-1.0)';
    'GPIOK5_SDA7':
      PIN_NUMBER='(0,P1,0,0,0,0,0)';
      BIDIRECTIONAL='TRUE';
      INPUT_LOAD='(-0.01,0.01)';
      OUTPUT_LOAD='(1.0,-1.0)';
    'GPIOK4_SCL7':
      PIN_NUMBER='(0,N1,0,0,0,0,0)';
      BIDIRECTIONAL='TRUE';
      INPUT_LOAD='(-0.01,0.01)';
      OUTPUT_LOAD='(1.0,-1.0)';
    'GPIOB5_LPCPD#_LPCSMI#':
      PIN_NUMBER='(0,H21,0,0,0,0,0)';
      BIDIRECTIONAL='TRUE';
      INPUT_LOAD='(-0.01,0.01)';
      OUTPUT_LOAD='(1.0,-1.0)';
    'GPIOQ4_SCL14':
      PIN_NUMBER='(0,N21,0,0,0,0,0)';
      BIDIRECTIONAL='TRUE';
      INPUT_LOAD='(-0.01,0.01)';
      OUTPUT_LOAD='(1.0,-1.0)';
    'GPIOQ5_SDA14':
      PIN_NUMBER='(0,N22,0,0,0,0,0)';
      BIDIRECTIONAL='TRUE';
      INPUT_LOAD='(-0.01,0.01)';
      OUTPUT_LOAD='(1.0,-1.0)';
    'GPIOC2_SD1DAT0_SCL11':
      PIN_NUMBER='(0,0,B12,0,0,0,0)';
      BIDIRECTIONAL='TRUE';
      INPUT_LOAD='(-0.01,0.01)';
      OUTPUT_LOAD='(1.0,-1.0)';
    'GPIOC3_SD1DAT1_SDA11':
      PIN_NUMBER='(0,0,D9,0,0,0,0)';
      BIDIRECTIONAL='TRUE';
      INPUT_LOAD='(-0.01,0.01)';
      OUTPUT_LOAD='(1.0,-1.0)';
    'GPIOC1_SD1CMD_SDA10':
      PIN_NUMBER='(0,0,A12,0,0,0,0)';
      BIDIRECTIONAL='TRUE';
      INPUT_LOAD='(-0.01,0.01)';
      OUTPUT_LOAD='(1.0,-1.0)';
    'GPIOC0_SD1CLK_SCL10':
      PIN_NUMBER='(0,0,C12,0,0,0,0)';
      BIDIRECTIONAL='TRUE';
      INPUT_LOAD='(-0.01,0.01)';
      OUTPUT_LOAD='(1.0,-1.0)';
    'GPIOA0_MAC1LINK':
      PIN_NUMBER='(0,0,B14,0,0,0,0)';
      BIDIRECTIONAL='TRUE';
      INPUT_LOAD='(-0.01,0.01)';
      OUTPUT_LOAD='(1.0,-1.0)';
    'GPIOA1_MAC2LINK':
      PIN_NUMBER='(0,0,D14,0,0,0,0)';
      BIDIRECTIONAL='TRUE';
      INPUT_LOAD='(-0.01,0.01)';
      OUTPUT_LOAD='(1.0,-1.0)';
    'GPIOY3_SIOONCTRL#':
      PIN_NUMBER='(0,0,P21,0,0,0,0)';
      BIDIRECTIONAL='TRUE';
      INPUT_LOAD='(-0.01,0.01)';
      OUTPUT_LOAD='(1.0,-1.0)';
    'GPIOG6_SGPS2I0_SALT3':
      PIN_NUMBER='(0,0,D15,0,0,0,0)';
      BIDIRECTIONAL='TRUE';
      INPUT_LOAD='(-0.01,0.01)';
      OUTPUT_LOAD='(1.0,-1.0)';
    'GPIOC6_SD1CD#_SCL13':
      PIN_NUMBER='(0,0,C11,0,0,0,0)';
      BIDIRECTIONAL='TRUE';
      INPUT_LOAD='(-0.01,0.01)';
      OUTPUT_LOAD='(1.0,-1.0)';
    'GPIOC4_SD1DAT2_SCL12':
      PIN_NUMBER='(0,0,D10,0,0,0,0)';
      BIDIRECTIONAL='TRUE';
      INPUT_LOAD='(-0.01,0.01)';
      OUTPUT_LOAD='(1.0,-1.0)';
    'GPIOG7_SGPS2I1_SALT4':
      PIN_NUMBER='(0,0,E14,0,0,0,0)';
      BIDIRECTIONAL='TRUE';
      INPUT_LOAD='(-0.01,0.01)';
      OUTPUT_LOAD='(1.0,-1.0)';
    'GPIOA2_TIMER3_SPI1CS1#':
      PIN_NUMBER='(0,0,D13,0,0,0,0)';
      BIDIRECTIONAL='TRUE';
      INPUT_LOAD='(-0.01,0.01)';
      OUTPUT_LOAD='(1.0,-1.0)';
    'GPIOG5_SGPS2LD_SALT2':
      PIN_NUMBER='(0,0,D16,0,0,0,0)';
      BIDIRECTIONAL='TRUE';
      INPUT_LOAD='(-0.01,0.01)';
      OUTPUT_LOAD='(1.0,-1.0)';
    'GPIOG4_SGPS2CK_SALT1':
      PIN_NUMBER='(0,0,E17,0,0,0,0)';
      BIDIRECTIONAL='TRUE';
      INPUT_LOAD='(-0.01,0.01)';
      OUTPUT_LOAD='(1.0,-1.0)';
    'GPIOF5_NRTS4_LHFRAME#':
      PIN_NUMBER='(0,0,H19,0,0,0,0)';
      BIDIRECTIONAL='TRUE';
      INPUT_LOAD='(-0.01,0.01)';
      OUTPUT_LOAD='(1.0,-1.0)';
    'GPIOF7_RXD4_LHRST#':
      PIN_NUMBER='(0,0,H18,0,0,0,0)';
      BIDIRECTIONAL='TRUE';
      INPUT_LOAD='(-0.01,0.01)';
      OUTPUT_LOAD='(1.0,-1.0)';
    'GPIOL2_NDSR1':
      PIN_NUMBER='(0,0,U1,0,0,0,0)';
      BIDIRECTIONAL='TRUE';
      INPUT_LOAD='(-0.01,0.01)';
      OUTPUT_LOAD='(1.0,-1.0)';
    'GPIOL3_NRI1_VPIHS':
      PIN_NUMBER='(0,0,U2,0,0,0,0)';
      BIDIRECTIONAL='TRUE';
      INPUT_LOAD='(-0.01,0.01)';
      OUTPUT_LOAD='(1.0,-1.0)';
    'GPIOL4_NDTR1_VPIVS':
      PIN_NUMBER='(0,0,P4,0,0,0,0)';
      BIDIRECTIONAL='TRUE';
      INPUT_LOAD='(-0.01,0.01)';
      OUTPUT_LOAD='(1.0,-1.0)';
    'PEREFCLKN':
      PIN_NUMBER='(0,0,K22,0,0,0,0)';
      INPUT_LOAD='(-0.01,0.01)';
    'PEREFCLKP':
      PIN_NUMBER='(0,0,K21,0,0,0,0)';
      INPUT_LOAD='(-0.01,0.01)';
    'RXD5':
      PIN_NUMBER='(0,0,K2,0,0,0,0)';
      INPUT_LOAD='(-0.01,0.01)';
    'PECI':
      PIN_NUMBER='(0,0,AB18,0,0,0,0)';
      BIDIRECTIONAL='TRUE';
      INPUT_LOAD='(-0.01,0.01)';
      OUTPUT_LOAD='(1.0,-1.0)';
    'GPIOD3_SD2DAT1':
      PIN_NUMBER='(0,0,D20,0,0,0,0)';
      BIDIRECTIONAL='TRUE';
      INPUT_LOAD='(-0.01,0.01)';
      OUTPUT_LOAD='(1.0,-1.0)';
    'GPIOD4_SD2DAT2':
      PIN_NUMBER='(0,0,D21,0,0,0,0)';
      BIDIRECTIONAL='TRUE';
      INPUT_LOAD='(-0.01,0.01)';
      OUTPUT_LOAD='(1.0,-1.0)';
    'GPIOD1_SD2CMD':
      PIN_NUMBER='(0,0,E21,0,0,0,0)';
      BIDIRECTIONAL='TRUE';
      INPUT_LOAD='(-0.01,0.01)';
      OUTPUT_LOAD='(1.0,-1.0)';
    'CLKIN':
      PIN_NUMBER='(0,0,W18,0,0,0,0)';
      INPUT_LOAD='(-0.01,0.01)';
    'SRST#':
      PIN_NUMBER='(0,0,U18,0,0,0,0)';
      INPUT_LOAD='(-0.01,0.01)';
    'GPIOA3_TIMER4':
      PIN_NUMBER='(0,0,E13,0,0,0,0)';
      BIDIRECTIONAL='TRUE';
      INPUT_LOAD='(-0.01,0.01)';
      OUTPUT_LOAD='(1.0,-1.0)';
    'PERST#':
      PIN_NUMBER='(0,0,L20,0,0,0,0)';
      BIDIRECTIONAL='TRUE';
      INPUT_LOAD='(-0.01,0.01)';
      OUTPUT_LOAD='(1.0,-1.0)';
    'PERXN':
      PIN_NUMBER='(0,0,M22,0,0,0,0)';
      INPUT_LOAD='(-0.01,0.01)';
    'PERXP':
      PIN_NUMBER='(0,0,M21,0,0,0,0)';
      INPUT_LOAD='(-0.01,0.01)';
    'GPIOM0_NCTS2_VPIB2':
      PIN_NUMBER='(0,0,Y1,0,0,0,0)';
      BIDIRECTIONAL='TRUE';
      INPUT_LOAD='(-0.01,0.01)';
      OUTPUT_LOAD='(1.0,-1.0)';
    'GPIOM1_NDCD2_VPIB3':
      PIN_NUMBER='(0,0,AB2,0,0,0,0)';
      BIDIRECTIONAL='TRUE';
      INPUT_LOAD='(-0.01,0.01)';
      OUTPUT_LOAD='(1.0,-1.0)';
    'GPIOM2_NDSR2_VPIB4':
      PIN_NUMBER='(0,0,AA1,0,0,0,0)';
      BIDIRECTIONAL='TRUE';
      INPUT_LOAD='(-0.01,0.01)';
      OUTPUT_LOAD='(1.0,-1.0)';
    'GPIOM3_NRI2_VPIB5':
      PIN_NUMBER='(0,0,Y2,0,0,0,0)';
      BIDIRECTIONAL='TRUE';
      INPUT_LOAD='(-0.01,0.01)';
      OUTPUT_LOAD='(1.0,-1.0)';
    'GPIOM4_NDTR2_VPIB6':
      PIN_NUMBER='(0,0,AA2,0,0,0,0)';
      BIDIRECTIONAL='TRUE';
      INPUT_LOAD='(-0.01,0.01)';
      OUTPUT_LOAD='(1.0,-1.0)';
    'GPIOM5_NRTS2_VPIB7':
      PIN_NUMBER='(0,0,P5,0,0,0,0)';
      BIDIRECTIONAL='TRUE';
      INPUT_LOAD='(-0.01,0.01)';
      OUTPUT_LOAD='(1.0,-1.0)';
    'GPIOM6_TXD2_VPIB8':
      PIN_NUMBER='(0,0,R5,0,0,0,0)';
      BIDIRECTIONAL='TRUE';
      INPUT_LOAD='(-0.01,0.01)';
      OUTPUT_LOAD='(1.0,-1.0)';
    'GPIOM7_RXD2_VPIB9':
      PIN_NUMBER='(0,0,T5,0,0,0,0)';
      BIDIRECTIONAL='TRUE';
      INPUT_LOAD='(-0.01,0.01)';
      OUTPUT_LOAD='(1.0,-1.0)';
    'GPIOL1_NDCD1_VPIDE':
      PIN_NUMBER='(0,0,T1,0,0,0,0)';
      BIDIRECTIONAL='TRUE';
      INPUT_LOAD='(-0.01,0.01)';
      OUTPUT_LOAD='(1.0,-1.0)';
    'GPIOL5_NRTS1_VPICLK':
      PIN_NUMBER='(0,0,P3,0,0,0,0)';
      BIDIRECTIONAL='TRUE';
      INPUT_LOAD='(-0.01,0.01)';
      OUTPUT_LOAD='(1.0,-1.0)';
    'GPIOL7_RXD1':
      PIN_NUMBER='(0,0,W1,0,0,0,0)';
      BIDIRECTIONAL='TRUE';
      INPUT_LOAD='(-0.01,0.01)';
      OUTPUT_LOAD='(1.0,-1.0)';
    'GPIOF0_NCTS4_LHAD0':
      PIN_NUMBER='(0,0,J19,0,0,0,0)';
      BIDIRECTIONAL='TRUE';
      INPUT_LOAD='(-0.01,0.01)';
      OUTPUT_LOAD='(1.0,-1.0)';
    'GPIOF1_NDCD4_LHAD1':
      PIN_NUMBER='(0,0,J18,0,0,0,0)';
      BIDIRECTIONAL='TRUE';
      INPUT_LOAD='(-0.01,0.01)';
      OUTPUT_LOAD='(1.0,-1.0)';
    'GPIOF2_NDSR4_LHAD2':
      PIN_NUMBER='(0,0,B22,0,0,0,0)';
      BIDIRECTIONAL='TRUE';
      INPUT_LOAD='(-0.01,0.01)';
      OUTPUT_LOAD='(1.0,-1.0)';
    'GPIOE2_NDSR3':
      PIN_NUMBER='(0,0,F18,0,0,0,0)';
      BIDIRECTIONAL='TRUE';
      INPUT_LOAD='(-0.01,0.01)';
      OUTPUT_LOAD='(1.0,-1.0)';
    'GPIOE3_NRI3':
      PIN_NUMBER='(0,0,F17,0,0,0,0)';
      BIDIRECTIONAL='TRUE';
      INPUT_LOAD='(-0.01,0.01)';
      OUTPUT_LOAD='(1.0,-1.0)';
    'GPIOE4_NDTR3':
      PIN_NUMBER='(0,0,E18,0,0,0,0)';
      BIDIRECTIONAL='TRUE';
      INPUT_LOAD='(-0.01,0.01)';
      OUTPUT_LOAD='(1.0,-1.0)';
    'GPIOE6_TXD3':
      PIN_NUMBER='(0,0,A20,0,0,0,0)';
      BIDIRECTIONAL='TRUE';
      INPUT_LOAD='(-0.01,0.01)';
      OUTPUT_LOAD='(1.0,-1.0)';
    'GPIOE7_RXD3':
      PIN_NUMBER='(0,0,B19,0,0,0,0)';
      BIDIRECTIONAL='TRUE';
      INPUT_LOAD='(-0.01,0.01)';
      OUTPUT_LOAD='(1.0,-1.0)';
    'TXD5':
      PIN_NUMBER='(0,0,K1,0,0,0,0)';
      OUTPUT_LOAD='(1.0,-1.0)';
    'PEREXT':
      PIN_NUMBER='(0,0,K20,0,0,0,0)';
      PIN_TYPE='ANALOG';
      NO_LOAD_CHECK='Both';
      NO_IO_CHECK='Both';
      NO_ASSERT_CHECK='TRUE';
      NO_DIR_CHECK='TRUE';
      ALLOW_CONNECT='TRUE';
    'PETXN':
      PIN_NUMBER='(0,0,L22,0,0,0,0)';
      OUTPUT_LOAD='(1.0,-1.0)';
    'PETXP':
      PIN_NUMBER='(0,0,L21,0,0,0,0)';
      OUTPUT_LOAD='(1.0,-1.0)';
    'GPIOE5_NRTS3':
      PIN_NUMBER='(0,0,D19,0,0,0,0)';
      BIDIRECTIONAL='TRUE';
      INPUT_LOAD='(-0.01,0.01)';
      OUTPUT_LOAD='(1.0,-1.0)';
    'GPIOE1_NDCD3':
      PIN_NUMBER='(0,0,C20,0,0,0,0)';
      BIDIRECTIONAL='TRUE';
      INPUT_LOAD='(-0.01,0.01)';
      OUTPUT_LOAD='(1.0,-1.0)';
    'GPIOE0_NCTS3':
      PIN_NUMBER='(0,0,B20,0,0,0,0)';
      BIDIRECTIONAL='TRUE';
      INPUT_LOAD='(-0.01,0.01)';
      OUTPUT_LOAD='(1.0,-1.0)';
    'GPIOD0_SD2CLK':
      PIN_NUMBER='(0,0,F19,0,0,0,0)';
      BIDIRECTIONAL='TRUE';
      INPUT_LOAD='(-0.01,0.01)';
      OUTPUT_LOAD='(1.0,-1.0)';
    'GPIOD2_SD2DAT0':
      PIN_NUMBER='(0,0,F20,0,0,0,0)';
      BIDIRECTIONAL='TRUE';
      INPUT_LOAD='(-0.01,0.01)';
      OUTPUT_LOAD='(1.0,-1.0)';
    'GPIOD7_SD2WP#':
      PIN_NUMBER='(0,0,C21,0,0,0,0)';
      BIDIRECTIONAL='TRUE';
      INPUT_LOAD='(-0.01,0.01)';
      OUTPUT_LOAD='(1.0,-1.0)';
    'GPIOC7_SD1WP#_SDA13':
      PIN_NUMBER='(0,0,B11,0,0,0,0)';
      BIDIRECTIONAL='TRUE';
      INPUT_LOAD='(-0.01,0.01)';
      OUTPUT_LOAD='(1.0,-1.0)';
    'GPIOC5_SD1DAT3_SDA12':
      PIN_NUMBER='(0,0,E12,0,0,0,0)';
      BIDIRECTIONAL='TRUE';
      INPUT_LOAD='(-0.01,0.01)';
      OUTPUT_LOAD='(1.0,-1.0)';
    'GPIOL0_NCTS1':
      PIN_NUMBER='(0,0,T2,0,0,0,0)';
      BIDIRECTIONAL='TRUE';
      INPUT_LOAD='(-0.01,0.01)';
      OUTPUT_LOAD='(1.0,-1.0)';
    'GPIOF3_NRI4_LHAD3':
      PIN_NUMBER='(0,0,B21,0,0,0,0)';
      BIDIRECTIONAL='TRUE';
      INPUT_LOAD='(-0.01,0.01)';
      OUTPUT_LOAD='(1.0,-1.0)';
    'GPIOF4_NDTR4_LHCLK':
      PIN_NUMBER='(0,0,A21,0,0,0,0)';
      BIDIRECTIONAL='TRUE';
      INPUT_LOAD='(-0.01,0.01)';
      OUTPUT_LOAD='(1.0,-1.0)';
    'GPIOF6_TXD4_LHSIRQ#':
      PIN_NUMBER='(0,0,G17,0,0,0,0)';
      BIDIRECTIONAL='TRUE';
      INPUT_LOAD='(-0.01,0.01)';
      OUTPUT_LOAD='(1.0,-1.0)';
    'GPIOL6_TXD1':
      PIN_NUMBER='(0,0,V1,0,0,0,0)';
      BIDIRECTIONAL='TRUE';
      INPUT_LOAD='(-0.01,0.01)';
      OUTPUT_LOAD='(1.0,-1.0)';
    'GPIOD6_SD2CD#':
      PIN_NUMBER='(0,0,G18,0,0,0,0)';
      BIDIRECTIONAL='TRUE';
      INPUT_LOAD='(-0.01,0.01)';
      OUTPUT_LOAD='(1.0,-1.0)';
    'GPIOD5_SD2DAT3':
      PIN_NUMBER='(0,0,E20,0,0,0,0)';
      BIDIRECTIONAL='TRUE';
      INPUT_LOAD='(-0.01,0.01)';
      OUTPUT_LOAD='(1.0,-1.0)';
    'USB2BVRES':
      PIN_NUMBER='(0,0,0,B7,0,0,0)';
      PIN_TYPE='ANALOG';
      NO_LOAD_CHECK='Both';
      NO_IO_CHECK='Both';
      NO_ASSERT_CHECK='TRUE';
      NO_DIR_CHECK='TRUE';
      ALLOW_CONNECT='TRUE';
    'USB2AVRES':
      PIN_NUMBER='(0,0,0,B8,0,0,0)';
      PIN_TYPE='ANALOG';
      NO_LOAD_CHECK='Both';
      NO_IO_CHECK='Both';
      NO_ASSERT_CHECK='TRUE';
      NO_DIR_CHECK='TRUE';
      ALLOW_CONNECT='TRUE';
    'GPIOH0_NCTS6':
      PIN_NUMBER='(0,0,0,A18,0,0,0)';
      BIDIRECTIONAL='TRUE';
      INPUT_LOAD='(-0.01,0.01)';
      OUTPUT_LOAD='(1.0,-1.0)';
    'GPIOH2_NDSR6':
      PIN_NUMBER='(0,0,0,D17,0,0,0)';
      BIDIRECTIONAL='TRUE';
      INPUT_LOAD='(-0.01,0.01)';
      OUTPUT_LOAD='(1.0,-1.0)';
    'GPIOH1_NDCD6':
      PIN_NUMBER='(0,0,0,B18,0,0,0)';
      BIDIRECTIONAL='TRUE';
      INPUT_LOAD='(-0.01,0.01)';
      OUTPUT_LOAD='(1.0,-1.0)';
    'GPIOH4_NDTR6':
      PIN_NUMBER='(0,0,0,A17,0,0,0)';
      BIDIRECTIONAL='TRUE';
      INPUT_LOAD='(-0.01,0.01)';
      OUTPUT_LOAD='(1.0,-1.0)';
    'GPIOH3_NRI6':
      PIN_NUMBER='(0,0,0,C17,0,0,0)';
      BIDIRECTIONAL='TRUE';
      INPUT_LOAD='(-0.01,0.01)';
      OUTPUT_LOAD='(1.0,-1.0)';
    'GPIOH5_NRTS6':
      PIN_NUMBER='(0,0,0,B17,0,0,0)';
      BIDIRECTIONAL='TRUE';
      INPUT_LOAD='(-0.01,0.01)';
      OUTPUT_LOAD='(1.0,-1.0)';
    'GPIOH7_RXD6':
      PIN_NUMBER='(0,0,0,D18,0,0,0)';
      BIDIRECTIONAL='TRUE';
      INPUT_LOAD='(-0.01,0.01)';
      OUTPUT_LOAD='(1.0,-1.0)';
    'GPIOH6_TXD6':
      PIN_NUMBER='(0,0,0,A16,0,0,0)';
      BIDIRECTIONAL='TRUE';
      INPUT_LOAD='(-0.01,0.01)';
      OUTPUT_LOAD='(1.0,-1.0)';
    'GPIOS0_VPOB2_SPI2CS1#':
      PIN_NUMBER='(0,0,0,V20,0,0,0)';
      BIDIRECTIONAL='TRUE';
      INPUT_LOAD='(-0.01,0.01)';
      OUTPUT_LOAD='(1.0,-1.0)';
    'GPIOS2_VPOB4_SALT5':
      PIN_NUMBER='(0,0,0,R18,0,0,0)';
      BIDIRECTIONAL='TRUE';
      INPUT_LOAD='(-0.01,0.01)';
      OUTPUT_LOAD='(1.0,-1.0)';
    'GPIOZ1_VPOG3_NORA1_SIOPWRGD':
      PIN_NUMBER='(0,0,0,AB20,0,0,0)';
      BIDIRECTIONAL='TRUE';
      INPUT_LOAD='(-0.01,0.01)';
      OUTPUT_LOAD='(1.0,-1.0)';
    'GPIOZ2_VPOG4_NORA2_SIOPBO#':
      PIN_NUMBER='(0,0,0,AB21,0,0,0)';
      BIDIRECTIONAL='TRUE';
      INPUT_LOAD='(-0.01,0.01)';
      OUTPUT_LOAD='(1.0,-1.0)';
    'GPIOZ3_VPOG5_NORA3_SIOSCI#':
      PIN_NUMBER='(0,0,0,AA21,0,0,0)';
      BIDIRECTIONAL='TRUE';
      INPUT_LOAD='(-0.01,0.01)';
      OUTPUT_LOAD='(1.0,-1.0)';
    'GPIOZ4_VPOG6_NORA4':
      PIN_NUMBER='(0,0,0,U21,0,0,0)';
      BIDIRECTIONAL='TRUE';
      INPUT_LOAD='(-0.01,0.01)';
      OUTPUT_LOAD='(1.0,-1.0)';
    'GPIOZ5_VPOG7_NORA5':
      PIN_NUMBER='(0,0,0,W22,0,0,0)';
      BIDIRECTIONAL='TRUE';
      INPUT_LOAD='(-0.01,0.01)';
      OUTPUT_LOAD='(1.0,-1.0)';
    'GPIOZ6_VPOG8_NORA6':
      PIN_NUMBER='(0,0,0,V22,0,0,0)';
      BIDIRECTIONAL='TRUE';
      INPUT_LOAD='(-0.01,0.01)';
      OUTPUT_LOAD='(1.0,-1.0)';
    'GPIOZ7_VPOG9_NORA7':
      PIN_NUMBER='(0,0,0,W21,0,0,0)';
      BIDIRECTIONAL='TRUE';
      INPUT_LOAD='(-0.01,0.01)';
      OUTPUT_LOAD='(1.0,-1.0)';
    'GPIOAA0_VPOR2_NORD0_SALT7':
      PIN_NUMBER='(0,0,0,Y21,0,0,0)';
      BIDIRECTIONAL='TRUE';
      INPUT_LOAD='(-0.01,0.01)';
      OUTPUT_LOAD='(1.0,-1.0)';
    'GPIOS3_VPOB5_SALT6':
      PIN_NUMBER='(0,0,0,P18,0,0,0)';
      BIDIRECTIONAL='TRUE';
      INPUT_LOAD='(-0.01,0.01)';
      OUTPUT_LOAD='(1.0,-1.0)';
    'GPIOS7_VPOB9':
      PIN_NUMBER='(0,0,0,AA20,0,0,0)';
      BIDIRECTIONAL='TRUE';
      INPUT_LOAD='(-0.01,0.01)';
      OUTPUT_LOAD='(1.0,-1.0)';
    'GPIOZ0_VPOG2_NORA0_SIOPBI#':
      PIN_NUMBER='(0,0,0,Y20,0,0,0)';
      BIDIRECTIONAL='TRUE';
      INPUT_LOAD='(-0.01,0.01)';
      OUTPUT_LOAD='(1.0,-1.0)';
    'GPIOAA2_VPOR4_NORD2_SALT9':
      PIN_NUMBER='(0,0,0,Y22,0,0,0)';
      BIDIRECTIONAL='TRUE';
      INPUT_LOAD='(-0.01,0.01)';
      OUTPUT_LOAD='(1.0,-1.0)';
    'USB2A_DP':
      PIN_NUMBER='(0,0,0,A7,0,0,0)';
      BIDIRECTIONAL='TRUE';
      INPUT_LOAD='(-0.01,0.01)';
      OUTPUT_LOAD='(1.0,-1.0)';
    'USB2A_DN':
      PIN_NUMBER='(0,0,0,A8,0,0,0)';
      BIDIRECTIONAL='TRUE';
      INPUT_LOAD='(-0.01,0.01)';
      OUTPUT_LOAD='(1.0,-1.0)';
    'USB2B_DP':
      PIN_NUMBER='(0,0,0,B6,0,0,0)';
      BIDIRECTIONAL='TRUE';
      INPUT_LOAD='(-0.01,0.01)';
      OUTPUT_LOAD='(1.0,-1.0)';
    'USB2B_DN':
      PIN_NUMBER='(0,0,0,A6,0,0,0)';
      BIDIRECTIONAL='TRUE';
      INPUT_LOAD='(-0.01,0.01)';
      OUTPUT_LOAD='(1.0,-1.0)';
    'GPIOS6_VPOB8':
      PIN_NUMBER='(0,0,0,U20,0,0,0)';
      BIDIRECTIONAL='TRUE';
      INPUT_LOAD='(-0.01,0.01)';
      OUTPUT_LOAD='(1.0,-1.0)';
    'GPIOS5_VPOB7':
      PIN_NUMBER='(0,0,0,W20,0,0,0)';
      BIDIRECTIONAL='TRUE';
      INPUT_LOAD='(-0.01,0.01)';
      OUTPUT_LOAD='(1.0,-1.0)';
    'GPIOS4_VPOB6':
      PIN_NUMBER='(0,0,0,R19,0,0,0)';
      BIDIRECTIONAL='TRUE';
      INPUT_LOAD='(-0.01,0.01)';
      OUTPUT_LOAD='(1.0,-1.0)';
    'GPIOS1_VPOB3_BMCINT':
      PIN_NUMBER='(0,0,0,U19,0,0,0)';
      BIDIRECTIONAL='TRUE';
      INPUT_LOAD='(-0.01,0.01)';
      OUTPUT_LOAD='(1.0,-1.0)';
    'GPIOAA1_VPOR3_NORD1_SALT8':
      PIN_NUMBER='(0,0,0,V21,0,0,0)';
      BIDIRECTIONAL='TRUE';
      INPUT_LOAD='(-0.01,0.01)';
      OUTPUT_LOAD='(1.0,-1.0)';
    'GPIOAA7_VPOR9_NORD7_SALT14':
      PIN_NUMBER='(0,0,0,P19,0,0,0)';
      BIDIRECTIONAL='TRUE';
      INPUT_LOAD='(-0.01,0.01)';
      OUTPUT_LOAD='(1.0,-1.0)';
    'GPIOAA6_VPOR8_NORD6_SALT13':
      PIN_NUMBER='(0,0,0,N18,0,0,0)';
      BIDIRECTIONAL='TRUE';
      INPUT_LOAD='(-0.01,0.01)';
      OUTPUT_LOAD='(1.0,-1.0)';
    'GPIOAA5_VPOR7_NORD5_SALT12':
      PIN_NUMBER='(0,0,0,T20,0,0,0)';
      BIDIRECTIONAL='TRUE';
      INPUT_LOAD='(-0.01,0.01)';
      OUTPUT_LOAD='(1.0,-1.0)';
    'GPIOAA4_VPOR6_NORD4_SALT11':
      PIN_NUMBER='(0,0,0,U22,0,0,0)';
      BIDIRECTIONAL='TRUE';
      INPUT_LOAD='(-0.01,0.01)';
      OUTPUT_LOAD='(1.0,-1.0)';
    'GPIOAA3_VPOR5_NORD3_SALT10':
      PIN_NUMBER='(0,0,0,AA22,0,0,0)';
      BIDIRECTIONAL='TRUE';
      INPUT_LOAD='(-0.01,0.01)';
      OUTPUT_LOAD='(1.0,-1.0)';
    'GPIOAC7_ESPIRST#_LPCRST#':
      PIN_NUMBER='(0,0,0,0,G22,0,0)';
      BIDIRECTIONAL='TRUE';
      INPUT_LOAD='(-0.01,0.01)';
      OUTPUT_LOAD='(1.0,-1.0)';
    'ENTEST':
      PIN_NUMBER='(0,0,0,0,K3,0,0)';
      INPUT_LOAD='(-0.01,0.01)';
    'EXTRST#':
      PIN_NUMBER='(0,0,0,0,V18,0,0)';
      INPUT_LOAD='(-0.01,0.01)';
    'GPIOQ6_OSCCLK':
      PIN_NUMBER='(0,0,0,0,B10,0,0)';
      BIDIRECTIONAL='TRUE';
      INPUT_LOAD='(-0.01,0.01)';
      OUTPUT_LOAD='(1.0,-1.0)';
    'GPIOQ7_PEWAKE#':
      PIN_NUMBER='(0,0,0,0,N20,0,0)';
      BIDIRECTIONAL='TRUE';
      INPUT_LOAD='(-0.01,0.01)';
      OUTPUT_LOAD='(1.0,-1.0)';
    'GPIOR5_SPI2MISO':
      PIN_NUMBER='(0,0,0,0,V19,0,0)';
      BIDIRECTIONAL='TRUE';
      INPUT_LOAD='(-0.01,0.01)';
      OUTPUT_LOAD='(1.0,-1.0)';
    'GPIOR2_SPI2CS0#':
      PIN_NUMBER='(0,0,0,0,T17,0,0)';
      BIDIRECTIONAL='TRUE';
      INPUT_LOAD='(-0.01,0.01)';
      OUTPUT_LOAD='(1.0,-1.0)';
    'GPIOR1_FWSPICS2#':
      PIN_NUMBER='(0,0,0,0,T19,0,0)';
      BIDIRECTIONAL='TRUE';
      INPUT_LOAD='(-0.01,0.01)';
      OUTPUT_LOAD='(1.0,-1.0)';
    'GPIOR0_FWSPICS1#':
      PIN_NUMBER='(0,0,0,0,AA19,0,0)';
      BIDIRECTIONAL='TRUE';
      INPUT_LOAD='(-0.01,0.01)';
      OUTPUT_LOAD='(1.0,-1.0)';
    'MRESET#':
      PIN_NUMBER='(0,0,0,0,AB17,0,0)';
      OUTPUT_LOAD='(1.0,-1.0)';
    'MALERT#':
      PIN_NUMBER='(0,0,0,0,U16,0,0)';
      BIDIRECTIONAL='TRUE';
      INPUT_LOAD='(-0.01,0.01)';
      OUTPUT_LOAD='(1.0,-1.0)';
    'HBLED#':
      PIN_NUMBER='(0,0,0,0,Y18,0,0)';
      OUTPUT_LOAD='(1.0,-1.0)';
    'GPIOJ4_VGAHS':
      PIN_NUMBER='(0,0,0,0,N5,0,0)';
      BIDIRECTIONAL='TRUE';
      INPUT_LOAD='(-0.01,0.01)';
      OUTPUT_LOAD='(1.0,-1.0)';
    'FWSPIMOSI':
      PIN_NUMBER='(0,0,0,0,U17,0,0)';
      BIDIRECTIONAL='TRUE';
      INPUT_LOAD='(-0.01,0.01)';
      OUTPUT_LOAD='(1.0,-1.0)';
    'FWSPICK':
      PIN_NUMBER='(0,0,0,0,AA18,0,0)';
      BIDIRECTIONAL='TRUE';
      INPUT_LOAD='(-0.01,0.01)';
      OUTPUT_LOAD='(1.0,-1.0)';
    'GPIOJ7_DDCDAT':
      PIN_NUMBER='(0,0,0,0,T3,0,0)';
      BIDIRECTIONAL='TRUE';
      INPUT_LOAD='(-0.01,0.01)';
      OUTPUT_LOAD='(1.0,-1.0)';
    'GPIOJ6_DDCCLK':
      PIN_NUMBER='(0,0,0,0,R3,0,0)';
      BIDIRECTIONAL='TRUE';
      INPUT_LOAD='(-0.01,0.01)';
      OUTPUT_LOAD='(1.0,-1.0)';
    'GPIOJ5_VGAVS':
      PIN_NUMBER='(0,0,0,0,R4,0,0)';
      BIDIRECTIONAL='TRUE';
      INPUT_LOAD='(-0.01,0.01)';
      OUTPUT_LOAD='(1.0,-1.0)';
    'GPIOAB3_VPOCLK_WDTRST2':
      PIN_NUMBER='(0,0,0,0,R20,0,0)';
      BIDIRECTIONAL='TRUE';
      INPUT_LOAD='(-0.01,0.01)';
      OUTPUT_LOAD='(1.0,-1.0)';
    'GPIOAB2_VPOVS_WDTRST1':
      PIN_NUMBER='(0,0,0,0,T22,0,0)';
      BIDIRECTIONAL='TRUE';
      INPUT_LOAD='(-0.01,0.01)';
      OUTPUT_LOAD='(1.0,-1.0)';
    'GPIOAB1_VPOHS_NORWE#':
      PIN_NUMBER='(0,0,0,0,T21,0,0)';
      BIDIRECTIONAL='TRUE';
      INPUT_LOAD='(-0.01,0.01)';
      OUTPUT_LOAD='(1.0,-1.0)';
    'GPIOAB0_VPODE_NOROE#':
      PIN_NUMBER='(0,0,0,0,N19,0,0)';
      BIDIRECTIONAL='TRUE';
      INPUT_LOAD='(-0.01,0.01)';
      OUTPUT_LOAD='(1.0,-1.0)';
    'GPIOAC4_ESPICK_LCLK':
      PIN_NUMBER='(0,0,0,0,C22,0,0)';
      BIDIRECTIONAL='TRUE';
      INPUT_LOAD='(-0.01,0.01)';
      OUTPUT_LOAD='(1.0,-1.0)';
    'GPIOAC3_ESPID3_LAD3':
      PIN_NUMBER='(0,0,0,0,E22,0,0)';
      BIDIRECTIONAL='TRUE';
      INPUT_LOAD='(-0.01,0.01)';
      OUTPUT_LOAD='(1.0,-1.0)';
    'GPIOAC2_ESPID2_LAD2':
      PIN_NUMBER='(0,0,0,0,D22,0,0)';
      BIDIRECTIONAL='TRUE';
      INPUT_LOAD='(-0.01,0.01)';
      OUTPUT_LOAD='(1.0,-1.0)';
    'GPIOAC1_ESPID1_LAD1':
      PIN_NUMBER='(0,0,0,0,G20,0,0)';
      BIDIRECTIONAL='TRUE';
      INPUT_LOAD='(-0.01,0.01)';
      OUTPUT_LOAD='(1.0,-1.0)';
    'GPIOAC0_ESPID0_LAD0':
      PIN_NUMBER='(0,0,0,0,G21,0,0)';
      BIDIRECTIONAL='TRUE';
      INPUT_LOAD='(-0.01,0.01)';
      OUTPUT_LOAD='(1.0,-1.0)';
    'FWSPIMISO':
      PIN_NUMBER='(0,0,0,0,T18,0,0)';
      BIDIRECTIONAL='TRUE';
      INPUT_LOAD='(-0.01,0.01)';
      OUTPUT_LOAD='(1.0,-1.0)';
    'FWSPICS0#':
      PIN_NUMBER='(0,0,0,0,AB19,0,0)';
      BIDIRECTIONAL='TRUE';
      INPUT_LOAD='(-0.01,0.01)';
      OUTPUT_LOAD='(1.0,-1.0)';
    'GPIOAC6_ESPIALT#_LSIRQ#':
      PIN_NUMBER='(0,0,0,0,F22,0,0)';
      BIDIRECTIONAL='TRUE';
      INPUT_LOAD='(-0.01,0.01)';
      OUTPUT_LOAD='(1.0,-1.0)';
    'GPIOAC5_ESPICS#_LFRAME#':
      PIN_NUMBER='(0,0,0,0,F21,0,0)';
      BIDIRECTIONAL='TRUE';
      INPUT_LOAD='(-0.01,0.01)';
      OUTPUT_LOAD='(1.0,-1.0)';
    'GPIOR3_SPI2CK':
      PIN_NUMBER='(0,0,0,0,Y19,0,0)';
      BIDIRECTIONAL='TRUE';
      INPUT_LOAD='(-0.01,0.01)';
      OUTPUT_LOAD='(1.0,-1.0)';
    'GPIOR4_SPI2MOSI':
      PIN_NUMBER='(0,0,0,0,W19,0,0)';
      BIDIRECTIONAL='TRUE';
      INPUT_LOAD='(-0.01,0.01)';
      OUTPUT_LOAD='(1.0,-1.0)';
    'ADC8_GPIX0':
      PIN_NUMBER='(0,0,0,0,0,F2,0)';
      INPUT_LOAD='(-0.01,0.01)';
    'ADC7_GPIW7':
      PIN_NUMBER='(0,0,0,0,0,G4,0)';
      INPUT_LOAD='(-0.01,0.01)';
    'GPIOA6_TIMER7_MDC2':
      PIN_NUMBER='(0,0,0,0,0,C13,0)';
      BIDIRECTIONAL='TRUE';
      INPUT_LOAD='(-0.01,0.01)';
      OUTPUT_LOAD='(1.0,-1.0)';
    'GPIOA7_TIMER8_MDIO2':
      PIN_NUMBER='(0,0,0,0,0,B13,0)';
      BIDIRECTIONAL='TRUE';
      INPUT_LOAD='(-0.01,0.01)';
      OUTPUT_LOAD='(1.0,-1.0)';
    'RGMIICK':
      PIN_NUMBER='(0,0,0,0,0,D3,0)';
      INPUT_LOAD='(-0.01,0.01)';
    'GPION6_PWM6_VPIG6':
      PIN_NUMBER='(0,0,0,0,0,Y3,0)';
      BIDIRECTIONAL='TRUE';
      INPUT_LOAD='(-0.01,0.01)';
      OUTPUT_LOAD='(1.0,-1.0)';
    'GPION7_PWM7_VPIG7':
      PIN_NUMBER='(0,0,0,0,0,T4,0)';
      BIDIRECTIONAL='TRUE';
      INPUT_LOAD='(-0.01,0.01)';
      OUTPUT_LOAD='(1.0,-1.0)';
    'GPION4_PWM4_VPIG4':
      PIN_NUMBER='(0,0,0,0,0,W3,0)';
      BIDIRECTIONAL='TRUE';
      INPUT_LOAD='(-0.01,0.01)';
      OUTPUT_LOAD='(1.0,-1.0)';
    'GPION5_PWM5_VPIG5':
      PIN_NUMBER='(0,0,0,0,0,AA3,0)';
      BIDIRECTIONAL='TRUE';
      INPUT_LOAD='(-0.01,0.01)';
      OUTPUT_LOAD='(1.0,-1.0)';
    'GPION3_PWM3_VPIG3':
      PIN_NUMBER='(0,0,0,0,0,U3,0)';
      BIDIRECTIONAL='TRUE';
      INPUT_LOAD='(-0.01,0.01)';
      OUTPUT_LOAD='(1.0,-1.0)';
    'GPION1_PWM1':
      PIN_NUMBER='(0,0,0,0,0,W2,0)';
      BIDIRECTIONAL='TRUE';
      INPUT_LOAD='(-0.01,0.01)';
      OUTPUT_LOAD='(1.0,-1.0)';
    'GPION2_PWM2_VPIG2':
      PIN_NUMBER='(0,0,0,0,0,V3,0)';
      BIDIRECTIONAL='TRUE';
      INPUT_LOAD='(-0.01,0.01)';
      OUTPUT_LOAD='(1.0,-1.0)';
    'GPION0_PWM0':
      PIN_NUMBER='(0,0,0,0,0,V2,0)';
      BIDIRECTIONAL='TRUE';
      INPUT_LOAD='(-0.01,0.01)';
      OUTPUT_LOAD='(1.0,-1.0)';
    'ADCVREFP':
      PIN_NUMBER='(0,0,0,0,0,H2,0)';
      OUTPUT_LOAD='(1.0,-1.0)';
    'ADCREXT':
      PIN_NUMBER='(0,0,0,0,0,J1,0)';
      OUTPUT_LOAD='(1.0,-1.0)';
    'ADCVREFN':
      PIN_NUMBER='(0,0,0,0,0,H1,0)';
      OUTPUT_LOAD='(1.0,-1.0)';
    'ADC14_GPIX6':
      PIN_NUMBER='(0,0,0,0,0,H3,0)';
      INPUT_LOAD='(-0.01,0.01)';
    'ADC15_GPIX7':
      PIN_NUMBER='(0,0,0,0,0,H4,0)';
      INPUT_LOAD='(-0.01,0.01)';
    'ADC13_GPIX5':
      PIN_NUMBER='(0,0,0,0,0,G1,0)';
      INPUT_LOAD='(-0.01,0.01)';
    'ADC12_GPIX4':
      PIN_NUMBER='(0,0,0,0,0,H5,0)';
      INPUT_LOAD='(-0.01,0.01)';
    'ADC11_GPIX3':
      PIN_NUMBER='(0,0,0,0,0,F1,0)';
      INPUT_LOAD='(-0.01,0.01)';
    'ADC9_GPIX1':
      PIN_NUMBER='(0,0,0,0,0,G3,0)';
      INPUT_LOAD='(-0.01,0.01)';
    'ADC10_GPIX2':
      PIN_NUMBER='(0,0,0,0,0,G2,0)';
      INPUT_LOAD='(-0.01,0.01)';
    'ADC6_GPIW6':
      PIN_NUMBER='(0,0,0,0,0,G5,0)';
      INPUT_LOAD='(-0.01,0.01)';
    'ADC4_GPIW4':
      PIN_NUMBER='(0,0,0,0,0,F3,0)';
      INPUT_LOAD='(-0.01,0.01)';
    'ADC5_GPIW5':
      PIN_NUMBER='(0,0,0,0,0,E3,0)';
      INPUT_LOAD='(-0.01,0.01)';
    'ADC3_GPIW3':
      PIN_NUMBER='(0,0,0,0,0,E1,0)';
      INPUT_LOAD='(-0.01,0.01)';
    'ADC2_GPIW2':
      PIN_NUMBER='(0,0,0,0,0,E2,0)';
      INPUT_LOAD='(-0.01,0.01)';
    'ADC1_GPIW1':
      PIN_NUMBER='(0,0,0,0,0,F5,0)';
      INPUT_LOAD='(-0.01,0.01)';
    'ADC0_GPIW0':
      PIN_NUMBER='(0,0,0,0,0,F4,0)';
      INPUT_LOAD='(-0.01,0.01)';
    'GPIOP7_TACH15':
      PIN_NUMBER='(0,0,0,0,0,V6,0)';
      BIDIRECTIONAL='TRUE';
      INPUT_LOAD='(-0.01,0.01)';
      OUTPUT_LOAD='(1.0,-1.0)';
    'GPIOP6_TACH14':
      PIN_NUMBER='(0,0,0,0,0,W6,0)';
      BIDIRECTIONAL='TRUE';
      INPUT_LOAD='(-0.01,0.01)';
      OUTPUT_LOAD='(1.0,-1.0)';
    'GPIOP3_TACH11_VPIR9':
      PIN_NUMBER='(0,0,0,0,0,AB5,0)';
      BIDIRECTIONAL='TRUE';
      INPUT_LOAD='(-0.01,0.01)';
      OUTPUT_LOAD='(1.0,-1.0)';
    'GPIOP4_TACH12':
      PIN_NUMBER='(0,0,0,0,0,Y6,0)';
      BIDIRECTIONAL='TRUE';
      INPUT_LOAD='(-0.01,0.01)';
      OUTPUT_LOAD='(1.0,-1.0)';
    'GPIOP5_TACH13':
      PIN_NUMBER='(0,0,0,0,0,Y5,0)';
      BIDIRECTIONAL='TRUE';
      INPUT_LOAD='(-0.01,0.01)';
      OUTPUT_LOAD='(1.0,-1.0)';
    'GPIOP2_TACH10_VPIR8':
      PIN_NUMBER='(0,0,0,0,0,AA5,0)';
      BIDIRECTIONAL='TRUE';
      INPUT_LOAD='(-0.01,0.01)';
      OUTPUT_LOAD='(1.0,-1.0)';
    'GPIOP1_TACH9_VPIR7':
      PIN_NUMBER='(0,0,0,0,0,W5,0)';
      BIDIRECTIONAL='TRUE';
      INPUT_LOAD='(-0.01,0.01)';
      OUTPUT_LOAD='(1.0,-1.0)';
    'GPIOO6_TACH6_VPIR4':
      PIN_NUMBER='(0,0,0,0,0,AA4,0)';
      BIDIRECTIONAL='TRUE';
      INPUT_LOAD='(-0.01,0.01)';
      OUTPUT_LOAD='(1.0,-1.0)';
    'GPIOO7_TACH7_VPIR5':
      PIN_NUMBER='(0,0,0,0,0,W4,0)';
      BIDIRECTIONAL='TRUE';
      INPUT_LOAD='(-0.01,0.01)';
      OUTPUT_LOAD='(1.0,-1.0)';
    'GPIOP0_TACH8_VPIR6':
      PIN_NUMBER='(0,0,0,0,0,V4,0)';
      BIDIRECTIONAL='TRUE';
      INPUT_LOAD='(-0.01,0.01)';
      OUTPUT_LOAD='(1.0,-1.0)';
    'GPIOO4_TACH4_VPIR2':
      PIN_NUMBER='(0,0,0,0,0,AB3,0)';
      BIDIRECTIONAL='TRUE';
      INPUT_LOAD='(-0.01,0.01)';
      OUTPUT_LOAD='(1.0,-1.0)';
    'GPIOO5_TACH5_VPIR3':
      PIN_NUMBER='(0,0,0,0,0,Y4,0)';
      BIDIRECTIONAL='TRUE';
      INPUT_LOAD='(-0.01,0.01)';
      OUTPUT_LOAD='(1.0,-1.0)';
    'GPIOO3_TACH3':
      PIN_NUMBER='(0,0,0,0,0,AB4,0)';
      BIDIRECTIONAL='TRUE';
      INPUT_LOAD='(-0.01,0.01)';
      OUTPUT_LOAD='(1.0,-1.0)';
    'GPIOO1_TACH1_VPIG9':
      PIN_NUMBER='(0,0,0,0,0,U4,0)';
      BIDIRECTIONAL='TRUE';
      INPUT_LOAD='(-0.01,0.01)';
      OUTPUT_LOAD='(1.0,-1.0)';
    'GPIOO2_TACH2':
      PIN_NUMBER='(0,0,0,0,0,V5,0)';
      BIDIRECTIONAL='TRUE';
      INPUT_LOAD='(-0.01,0.01)';
      OUTPUT_LOAD='(1.0,-1.0)';
    'GPIOO0_TACH0_VPIG8':
      PIN_NUMBER='(0,0,0,0,0,U5,0)';
      BIDIRECTIONAL='TRUE';
      INPUT_LOAD='(-0.01,0.01)';
      OUTPUT_LOAD='(1.0,-1.0)';
    'RGMII2TXCTL_RMII2TXEN_GPIOT7':
      PIN_NUMBER='(0,0,0,0,0,B1,0)';
      OUTPUT_LOAD='(1.0,-1.0)';
    'RGMII2TXCK_RMII2RCLKO_GPIOT6':
      PIN_NUMBER='(0,0,0,0,0,B2,0)';
      OUTPUT_LOAD='(1.0,-1.0)';
    'RGMII2TXD2_GPIOU2':
      PIN_NUMBER='(0,0,0,0,0,D5,0)';
      OUTPUT_LOAD='(1.0,-1.0)';
    'RGMII2TXD3_GPIOU3':
      PIN_NUMBER='(0,0,0,0,0,D4,0)';
      OUTPUT_LOAD='(1.0,-1.0)';
    'RGMII2TXD1_RMII2TXD1_GPIOU1':
      PIN_NUMBER='(0,0,0,0,0,B3,0)';
      OUTPUT_LOAD='(1.0,-1.0)';
    'RGMII2TXD0_RMII2TXD0_GPIOU0':
      PIN_NUMBER='(0,0,0,0,0,A2,0)';
      OUTPUT_LOAD='(1.0,-1.0)';
    'RGMII1TXCK_RMII1RCLKO_GPIOT0':
      PIN_NUMBER='(0,0,0,0,0,B5,0)';
      OUTPUT_LOAD='(1.0,-1.0)';
    'RGMII1TXCTL_RMII1TXEN_GPIOT1':
      PIN_NUMBER='(0,0,0,0,0,E9,0)';
      OUTPUT_LOAD='(1.0,-1.0)';
    'RGMII1TXD2_GPIOT4':
      PIN_NUMBER='(0,0,0,0,0,E7,0)';
      OUTPUT_LOAD='(1.0,-1.0)';
    'RGMII1TXD3_GPIOT5':
      PIN_NUMBER='(0,0,0,0,0,D7,0)';
      OUTPUT_LOAD='(1.0,-1.0)';
    'RGMII1TXD0_RMII1TXD0_GPIOT2':
      PIN_NUMBER='(0,0,0,0,0,F9,0)';
      OUTPUT_LOAD='(1.0,-1.0)';
    'RGMII1TXD1_RMII1TXD1_GPIOT3':
      PIN_NUMBER='(0,0,0,0,0,A5,0)';
      OUTPUT_LOAD='(1.0,-1.0)';
    'RGMII2RXCTL_GPIOV3':
      PIN_NUMBER='(0,0,0,0,0,C1,0)';
      BIDIRECTIONAL='TRUE';
      INPUT_LOAD='(-0.01,0.01)';
      OUTPUT_LOAD='(1.0,-1.0)';
    'GPIOR6_MDC1':
      PIN_NUMBER='(0,0,0,0,0,D8,0)';
      BIDIRECTIONAL='TRUE';
      INPUT_LOAD='(-0.01,0.01)';
      OUTPUT_LOAD='(1.0,-1.0)';
    'GPIOR7_MDIO1':
      PIN_NUMBER='(0,0,0,0,0,E10,0)';
      BIDIRECTIONAL='TRUE';
      INPUT_LOAD='(-0.01,0.01)';
      OUTPUT_LOAD='(1.0,-1.0)';
    'RGMII1RXD0_RMII1RXD0_GPIOU6':
      PIN_NUMBER='(0,0,0,0,0,A3,0)';
      BIDIRECTIONAL='TRUE';
      INPUT_LOAD='(-0.01,0.01)';
      OUTPUT_LOAD='(1.0,-1.0)';
    'RGMII1RXD1_RMII1RXD1_GPIOU7':
      PIN_NUMBER='(0,0,0,0,0,D6,0)';
      BIDIRECTIONAL='TRUE';
      INPUT_LOAD='(-0.01,0.01)';
      OUTPUT_LOAD='(1.0,-1.0)';
    'RGMII1RXD2_RMII1CRSDV_GPIOV0':
      PIN_NUMBER='(0,0,0,0,0,C5,0)';
      BIDIRECTIONAL='TRUE';
      INPUT_LOAD='(-0.01,0.01)';
      OUTPUT_LOAD='(1.0,-1.0)';
    'RGMII1RXD3_RMII1RXER_GPIOV1':
      PIN_NUMBER='(0,0,0,0,0,C4,0)';
      BIDIRECTIONAL='TRUE';
      INPUT_LOAD='(-0.01,0.01)';
      OUTPUT_LOAD='(1.0,-1.0)';
    'RGMII1RXCTL_GPIOU5':
      PIN_NUMBER='(0,0,0,0,0,A4,0)';
      BIDIRECTIONAL='TRUE';
      INPUT_LOAD='(-0.01,0.01)';
      OUTPUT_LOAD='(1.0,-1.0)';
    'RGMII1RXCK_RMII1RCLKI_GPIOU4':
      PIN_NUMBER='(0,0,0,0,0,B4,0)';
      BIDIRECTIONAL='TRUE';
      INPUT_LOAD='(-0.01,0.01)';
      OUTPUT_LOAD='(1.0,-1.0)';
    'RGMII2RXD0_RMII2RXD0_GPIOV4':
      PIN_NUMBER='(0,0,0,0,0,C3,0)';
      BIDIRECTIONAL='TRUE';
      INPUT_LOAD='(-0.01,0.01)';
      OUTPUT_LOAD='(1.0,-1.0)';
    'RGMII2RXD1_RMII2RXD1_GPIOV5':
      PIN_NUMBER='(0,0,0,0,0,D1,0)';
      BIDIRECTIONAL='TRUE';
      INPUT_LOAD='(-0.01,0.01)';
      OUTPUT_LOAD='(1.0,-1.0)';
    'RGMII2RXD2_RMII2CRSDV_GPIOV6':
      PIN_NUMBER='(0,0,0,0,0,D2,0)';
      BIDIRECTIONAL='TRUE';
      INPUT_LOAD='(-0.01,0.01)';
      OUTPUT_LOAD='(1.0,-1.0)';
    'RGMII2RXD3_RMII2RXER_GPIOV7':
      PIN_NUMBER='(0,0,0,0,0,E6,0)';
      BIDIRECTIONAL='TRUE';
      INPUT_LOAD='(-0.01,0.01)';
      OUTPUT_LOAD='(1.0,-1.0)';
    'RGMII2RXCK_RMII2RCLKI_GPIOV2':
      PIN_NUMBER='(0,0,0,0,0,C2,0)';
      BIDIRECTIONAL='TRUE';
      INPUT_LOAD='(-0.01,0.01)';
      OUTPUT_LOAD='(1.0,-1.0)';
    'LPVDD1':
      PIN_NUMBER='(0,0,0,0,0,0,K17)';
      PINUSE='POWER';
      NO_LOAD_CHECK='Both';
      NO_IO_CHECK='Both';
      NO_ASSERT_CHECK='TRUE';
      NO_DIR_CHECK='TRUE';
      ALLOW_CONNECT='TRUE';
    'LPVDD0':
      PIN_NUMBER='(0,0,0,0,0,0,J17)';
      PINUSE='POWER';
      NO_LOAD_CHECK='Both';
      NO_IO_CHECK='Both';
      NO_ASSERT_CHECK='TRUE';
      NO_DIR_CHECK='TRUE';
      ALLOW_CONNECT='TRUE';
    'GND68':
      PIN_NUMBER='(0,0,0,0,0,0,E5)';
      PINUSE='POWER';
      NO_LOAD_CHECK='Both';
      NO_IO_CHECK='Both';
      NO_ASSERT_CHECK='TRUE';
      NO_DIR_CHECK='TRUE';
      ALLOW_CONNECT='TRUE';
    'DACAV33':
      PIN_NUMBER='(0,0,0,0,0,0,K6)';
      PINUSE='POWER';
      NO_LOAD_CHECK='Both';
      NO_IO_CHECK='Both';
      NO_ASSERT_CHECK='TRUE';
      NO_DIR_CHECK='TRUE';
      ALLOW_CONNECT='TRUE';
    'PV33D0':
      PIN_NUMBER='(0,0,0,0,0,0,F12)';
      PINUSE='POWER';
      NO_LOAD_CHECK='Both';
      NO_IO_CHECK='Both';
      NO_ASSERT_CHECK='TRUE';
      NO_DIR_CHECK='TRUE';
      ALLOW_CONNECT='TRUE';
    'MVDD4':
      PIN_NUMBER='(0,0,0,0,0,0,T8)';
      PINUSE='POWER';
      NO_LOAD_CHECK='Both';
      NO_IO_CHECK='Both';
      NO_ASSERT_CHECK='TRUE';
      NO_DIR_CHECK='TRUE';
      ALLOW_CONNECT='TRUE';
    'GPIOY2_SIOPWREQ#':
      PIN_NUMBER='(0,0,0,0,0,0,P22)';
      BIDIRECTIONAL='TRUE';
      INPUT_LOAD='(-0.01,0.01)';
      OUTPUT_LOAD='(1.0,-1.0)';
    'GPIOY1_SIOS5#':
      PIN_NUMBER='(0,0,0,0,0,0,R21)';
      BIDIRECTIONAL='TRUE';
      INPUT_LOAD='(-0.01,0.01)';
      OUTPUT_LOAD='(1.0,-1.0)';
    'GPIOY0_SIOS3#':
      PIN_NUMBER='(0,0,0,0,0,0,R22)';
      BIDIRECTIONAL='TRUE';
      INPUT_LOAD='(-0.01,0.01)';
      OUTPUT_LOAD='(1.0,-1.0)';
    'IV11D0':
      PIN_NUMBER='(0,0,0,0,0,0,F6)';
      PINUSE='POWER';
      NO_LOAD_CHECK='Both';
      NO_IO_CHECK='Both';
      NO_ASSERT_CHECK='TRUE';
      NO_DIR_CHECK='TRUE';
      ALLOW_CONNECT='TRUE';
    'IV11D1':
      PIN_NUMBER='(0,0,0,0,0,0,G10)';
      PINUSE='POWER';
      NO_LOAD_CHECK='Both';
      NO_IO_CHECK='Both';
      NO_ASSERT_CHECK='TRUE';
      NO_DIR_CHECK='TRUE';
      ALLOW_CONNECT='TRUE';
    'IV11D2':
      PIN_NUMBER='(0,0,0,0,0,0,G11)';
      PINUSE='POWER';
      NO_LOAD_CHECK='Both';
      NO_IO_CHECK='Both';
      NO_ASSERT_CHECK='TRUE';
      NO_DIR_CHECK='TRUE';
      ALLOW_CONNECT='TRUE';
    'IV11D3':
      PIN_NUMBER='(0,0,0,0,0,0,G12)';
      PINUSE='POWER';
      NO_LOAD_CHECK='Both';
      NO_IO_CHECK='Both';
      NO_ASSERT_CHECK='TRUE';
      NO_DIR_CHECK='TRUE';
      ALLOW_CONNECT='TRUE';
    'IV11D4':
      PIN_NUMBER='(0,0,0,0,0,0,G13)';
      PINUSE='POWER';
      NO_LOAD_CHECK='Both';
      NO_IO_CHECK='Both';
      NO_ASSERT_CHECK='TRUE';
      NO_DIR_CHECK='TRUE';
      ALLOW_CONNECT='TRUE';
    'IV11D5':
      PIN_NUMBER='(0,0,0,0,0,0,G14)';
      PINUSE='POWER';
      NO_LOAD_CHECK='Both';
      NO_IO_CHECK='Both';
      NO_ASSERT_CHECK='TRUE';
      NO_DIR_CHECK='TRUE';
      ALLOW_CONNECT='TRUE';
    'IV11D6':
      PIN_NUMBER='(0,0,0,0,0,0,G15)';
      PINUSE='POWER';
      NO_LOAD_CHECK='Both';
      NO_IO_CHECK='Both';
      NO_ASSERT_CHECK='TRUE';
      NO_DIR_CHECK='TRUE';
      ALLOW_CONNECT='TRUE';
    'IV11D7':
      PIN_NUMBER='(0,0,0,0,0,0,G7)';
      PINUSE='POWER';
      NO_LOAD_CHECK='Both';
      NO_IO_CHECK='Both';
      NO_ASSERT_CHECK='TRUE';
      NO_DIR_CHECK='TRUE';
      ALLOW_CONNECT='TRUE';
    'IV11D8':
      PIN_NUMBER='(0,0,0,0,0,0,G8)';
      PINUSE='POWER';
      NO_LOAD_CHECK='Both';
      NO_IO_CHECK='Both';
      NO_ASSERT_CHECK='TRUE';
      NO_DIR_CHECK='TRUE';
      ALLOW_CONNECT='TRUE';
    'IV11D9':
      PIN_NUMBER='(0,0,0,0,0,0,G9)';
      PINUSE='POWER';
      NO_LOAD_CHECK='Both';
      NO_IO_CHECK='Both';
      NO_ASSERT_CHECK='TRUE';
      NO_DIR_CHECK='TRUE';
      ALLOW_CONNECT='TRUE';
    'IV11D10':
      PIN_NUMBER='(0,0,0,0,0,0,H16)';
      PINUSE='POWER';
      NO_LOAD_CHECK='Both';
      NO_IO_CHECK='Both';
      NO_ASSERT_CHECK='TRUE';
      NO_DIR_CHECK='TRUE';
      ALLOW_CONNECT='TRUE';
    'IV11D11':
      PIN_NUMBER='(0,0,0,0,0,0,J16)';
      PINUSE='POWER';
      NO_LOAD_CHECK='Both';
      NO_IO_CHECK='Both';
      NO_ASSERT_CHECK='TRUE';
      NO_DIR_CHECK='TRUE';
      ALLOW_CONNECT='TRUE';
    'IV11D12':
      PIN_NUMBER='(0,0,0,0,0,0,L7)';
      PINUSE='POWER';
      NO_LOAD_CHECK='Both';
      NO_IO_CHECK='Both';
      NO_ASSERT_CHECK='TRUE';
      NO_DIR_CHECK='TRUE';
      ALLOW_CONNECT='TRUE';
    'IV11D13':
      PIN_NUMBER='(0,0,0,0,0,0,N16)';
      PINUSE='POWER';
      NO_LOAD_CHECK='Both';
      NO_IO_CHECK='Both';
      NO_ASSERT_CHECK='TRUE';
      NO_DIR_CHECK='TRUE';
      ALLOW_CONNECT='TRUE';
    'IV11D14':
      PIN_NUMBER='(0,0,0,0,0,0,N7)';
      PINUSE='POWER';
      NO_LOAD_CHECK='Both';
      NO_IO_CHECK='Both';
      NO_ASSERT_CHECK='TRUE';
      NO_DIR_CHECK='TRUE';
      ALLOW_CONNECT='TRUE';
    'IV11D15':
      PIN_NUMBER='(0,0,0,0,0,0,P10)';
      PINUSE='POWER';
      NO_LOAD_CHECK='Both';
      NO_IO_CHECK='Both';
      NO_ASSERT_CHECK='TRUE';
      NO_DIR_CHECK='TRUE';
      ALLOW_CONNECT='TRUE';
    'IV11D16':
      PIN_NUMBER='(0,0,0,0,0,0,P11)';
      PINUSE='POWER';
      NO_LOAD_CHECK='Both';
      NO_IO_CHECK='Both';
      NO_ASSERT_CHECK='TRUE';
      NO_DIR_CHECK='TRUE';
      ALLOW_CONNECT='TRUE';
    'IV11D17':
      PIN_NUMBER='(0,0,0,0,0,0,P12)';
      PINUSE='POWER';
      NO_LOAD_CHECK='Both';
      NO_IO_CHECK='Both';
      NO_ASSERT_CHECK='TRUE';
      NO_DIR_CHECK='TRUE';
      ALLOW_CONNECT='TRUE';
    'IV11D18':
      PIN_NUMBER='(0,0,0,0,0,0,P13)';
      PINUSE='POWER';
      NO_LOAD_CHECK='Both';
      NO_IO_CHECK='Both';
      NO_ASSERT_CHECK='TRUE';
      NO_DIR_CHECK='TRUE';
      ALLOW_CONNECT='TRUE';
    'IV11D19':
      PIN_NUMBER='(0,0,0,0,0,0,P14)';
      PINUSE='POWER';
      NO_LOAD_CHECK='Both';
      NO_IO_CHECK='Both';
      NO_ASSERT_CHECK='TRUE';
      NO_DIR_CHECK='TRUE';
      ALLOW_CONNECT='TRUE';
    'IV11D20':
      PIN_NUMBER='(0,0,0,0,0,0,P16)';
      PINUSE='POWER';
      NO_LOAD_CHECK='Both';
      NO_IO_CHECK='Both';
      NO_ASSERT_CHECK='TRUE';
      NO_DIR_CHECK='TRUE';
      ALLOW_CONNECT='TRUE';
    'IV11D21':
      PIN_NUMBER='(0,0,0,0,0,0,P7)';
      PINUSE='POWER';
      NO_LOAD_CHECK='Both';
      NO_IO_CHECK='Both';
      NO_ASSERT_CHECK='TRUE';
      NO_DIR_CHECK='TRUE';
      ALLOW_CONNECT='TRUE';
    'IV11D22':
      PIN_NUMBER='(0,0,0,0,0,0,P9)';
      PINUSE='POWER';
      NO_LOAD_CHECK='Both';
      NO_IO_CHECK='Both';
      NO_ASSERT_CHECK='TRUE';
      NO_DIR_CHECK='TRUE';
      ALLOW_CONNECT='TRUE';
    'IV11D23':
      PIN_NUMBER='(0,0,0,0,0,0,R16)';
      PINUSE='POWER';
      NO_LOAD_CHECK='Both';
      NO_IO_CHECK='Both';
      NO_ASSERT_CHECK='TRUE';
      NO_DIR_CHECK='TRUE';
      ALLOW_CONNECT='TRUE';
    'IV11D24':
      PIN_NUMBER='(0,0,0,0,0,0,R7)';
      PINUSE='POWER';
      NO_LOAD_CHECK='Both';
      NO_IO_CHECK='Both';
      NO_ASSERT_CHECK='TRUE';
      NO_DIR_CHECK='TRUE';
      ALLOW_CONNECT='TRUE';
    'VPLLAV110':
      PIN_NUMBER='(0,0,0,0,0,0,L5)';
      PINUSE='POWER';
      NO_LOAD_CHECK='Both';
      NO_IO_CHECK='Both';
      NO_ASSERT_CHECK='TRUE';
      NO_DIR_CHECK='TRUE';
      ALLOW_CONNECT='TRUE';
    'VPLLAV111':
      PIN_NUMBER='(0,0,0,0,0,0,L6)';
      PINUSE='POWER';
      NO_LOAD_CHECK='Both';
      NO_IO_CHECK='Both';
      NO_ASSERT_CHECK='TRUE';
      NO_DIR_CHECK='TRUE';
      ALLOW_CONNECT='TRUE';
    'PEAV11':
      PIN_NUMBER='(0,0,0,0,0,0,L17)';
      PINUSE='POWER';
      NO_LOAD_CHECK='Both';
      NO_IO_CHECK='Both';
      NO_ASSERT_CHECK='TRUE';
      NO_DIR_CHECK='TRUE';
      ALLOW_CONNECT='TRUE';
    'PLLDV11':
      PIN_NUMBER='(0,0,0,0,0,0,V17)';
      PINUSE='POWER';
      NO_LOAD_CHECK='Both';
      NO_IO_CHECK='Both';
      NO_ASSERT_CHECK='TRUE';
      NO_DIR_CHECK='TRUE';
      ALLOW_CONNECT='TRUE';
    'PECIVDD':
      PIN_NUMBER='(0,0,0,0,0,0,AA17)';
      PINUSE='POWER';
      NO_LOAD_CHECK='Both';
      NO_IO_CHECK='Both';
      NO_ASSERT_CHECK='TRUE';
      NO_DIR_CHECK='TRUE';
      ALLOW_CONNECT='TRUE';
    'MVDD0':
      PIN_NUMBER='(0,0,0,0,0,0,T10)';
      PINUSE='POWER';
      NO_LOAD_CHECK='Both';
      NO_IO_CHECK='Both';
      NO_ASSERT_CHECK='TRUE';
      NO_DIR_CHECK='TRUE';
      ALLOW_CONNECT='TRUE';
    'MVDD1':
      PIN_NUMBER='(0,0,0,0,0,0,T12)';
      PINUSE='POWER';
      NO_LOAD_CHECK='Both';
      NO_IO_CHECK='Both';
      NO_ASSERT_CHECK='TRUE';
      NO_DIR_CHECK='TRUE';
      ALLOW_CONNECT='TRUE';
    'MVDD2':
      PIN_NUMBER='(0,0,0,0,0,0,T13)';
      PINUSE='POWER';
      NO_LOAD_CHECK='Both';
      NO_IO_CHECK='Both';
      NO_ASSERT_CHECK='TRUE';
      NO_DIR_CHECK='TRUE';
      ALLOW_CONNECT='TRUE';
    'MVDD3':
      PIN_NUMBER='(0,0,0,0,0,0,T14)';
      PINUSE='POWER';
      NO_LOAD_CHECK='Both';
      NO_IO_CHECK='Both';
      NO_ASSERT_CHECK='TRUE';
      NO_DIR_CHECK='TRUE';
      ALLOW_CONNECT='TRUE';
    'PV33D1':
      PIN_NUMBER='(0,0,0,0,0,0,F13)';
      PINUSE='POWER';
      NO_LOAD_CHECK='Both';
      NO_IO_CHECK='Both';
      NO_ASSERT_CHECK='TRUE';
      NO_DIR_CHECK='TRUE';
      ALLOW_CONNECT='TRUE';
    'PV33D2':
      PIN_NUMBER='(0,0,0,0,0,0,F14)';
      PINUSE='POWER';
      NO_LOAD_CHECK='Both';
      NO_IO_CHECK='Both';
      NO_ASSERT_CHECK='TRUE';
      NO_DIR_CHECK='TRUE';
      ALLOW_CONNECT='TRUE';
    'PV33D3':
      PIN_NUMBER='(0,0,0,0,0,0,F15)';
      PINUSE='POWER';
      NO_LOAD_CHECK='Both';
      NO_IO_CHECK='Both';
      NO_ASSERT_CHECK='TRUE';
      NO_DIR_CHECK='TRUE';
      ALLOW_CONNECT='TRUE';
    'PV33D4':
      PIN_NUMBER='(0,0,0,0,0,0,G16)';
      PINUSE='POWER';
      NO_LOAD_CHECK='Both';
      NO_IO_CHECK='Both';
      NO_ASSERT_CHECK='TRUE';
      NO_DIR_CHECK='TRUE';
      ALLOW_CONNECT='TRUE';
    'PV33D5':
      PIN_NUMBER='(0,0,0,0,0,0,H17)';
      PINUSE='POWER';
      NO_LOAD_CHECK='Both';
      NO_IO_CHECK='Both';
      NO_ASSERT_CHECK='TRUE';
      NO_DIR_CHECK='TRUE';
      ALLOW_CONNECT='TRUE';
    'PV33D6':
      PIN_NUMBER='(0,0,0,0,0,0,K7)';
      PINUSE='POWER';
      NO_LOAD_CHECK='Both';
      NO_IO_CHECK='Both';
      NO_ASSERT_CHECK='TRUE';
      NO_DIR_CHECK='TRUE';
      ALLOW_CONNECT='TRUE';
    'PV33D7':
      PIN_NUMBER='(0,0,0,0,0,0,N17)';
      PINUSE='POWER';
      NO_LOAD_CHECK='Both';
      NO_IO_CHECK='Both';
      NO_ASSERT_CHECK='TRUE';
      NO_DIR_CHECK='TRUE';
      ALLOW_CONNECT='TRUE';
    'PV33D8':
      PIN_NUMBER='(0,0,0,0,0,0,N6)';
      PINUSE='POWER';
      NO_LOAD_CHECK='Both';
      NO_IO_CHECK='Both';
      NO_ASSERT_CHECK='TRUE';
      NO_DIR_CHECK='TRUE';
      ALLOW_CONNECT='TRUE';
    'PV33D9':
      PIN_NUMBER='(0,0,0,0,0,0,P17)';
      PINUSE='POWER';
      NO_LOAD_CHECK='Both';
      NO_IO_CHECK='Both';
      NO_ASSERT_CHECK='TRUE';
      NO_DIR_CHECK='TRUE';
      ALLOW_CONNECT='TRUE';
    'PV33D10':
      PIN_NUMBER='(0,0,0,0,0,0,P6)';
      PINUSE='POWER';
      NO_LOAD_CHECK='Both';
      NO_IO_CHECK='Both';
      NO_ASSERT_CHECK='TRUE';
      NO_DIR_CHECK='TRUE';
      ALLOW_CONNECT='TRUE';
    'PV33D11':
      PIN_NUMBER='(0,0,0,0,0,0,R17)';
      PINUSE='POWER';
      NO_LOAD_CHECK='Both';
      NO_IO_CHECK='Both';
      NO_ASSERT_CHECK='TRUE';
      NO_DIR_CHECK='TRUE';
      ALLOW_CONNECT='TRUE';
    'PV33D12':
      PIN_NUMBER='(0,0,0,0,0,0,R6)';
      PINUSE='POWER';
      NO_LOAD_CHECK='Both';
      NO_IO_CHECK='Both';
      NO_ASSERT_CHECK='TRUE';
      NO_DIR_CHECK='TRUE';
      ALLOW_CONNECT='TRUE';
    'PV33D13':
      PIN_NUMBER='(0,0,0,0,0,0,T11)';
      PINUSE='POWER';
      NO_LOAD_CHECK='Both';
      NO_IO_CHECK='Both';
      NO_ASSERT_CHECK='TRUE';
      NO_DIR_CHECK='TRUE';
      ALLOW_CONNECT='TRUE';
    'PV33D14':
      PIN_NUMBER='(0,0,0,0,0,0,T15)';
      PINUSE='POWER';
      NO_LOAD_CHECK='Both';
      NO_IO_CHECK='Both';
      NO_ASSERT_CHECK='TRUE';
      NO_DIR_CHECK='TRUE';
      ALLOW_CONNECT='TRUE';
    'PLLAV330':
      PIN_NUMBER='(0,0,0,0,0,0,Y17)';
      PINUSE='POWER';
      NO_LOAD_CHECK='Both';
      NO_IO_CHECK='Both';
      NO_ASSERT_CHECK='TRUE';
      NO_DIR_CHECK='TRUE';
      ALLOW_CONNECT='TRUE';
    'PLLAV331':
      PIN_NUMBER='(0,0,0,0,0,0,W17)';
      PINUSE='POWER';
      NO_LOAD_CHECK='Both';
      NO_IO_CHECK='Both';
      NO_ASSERT_CHECK='TRUE';
      NO_DIR_CHECK='TRUE';
      ALLOW_CONNECT='TRUE';
    'VPLLAV330':
      PIN_NUMBER='(0,0,0,0,0,0,J7)';
      PINUSE='POWER';
      NO_LOAD_CHECK='Both';
      NO_IO_CHECK='Both';
      NO_ASSERT_CHECK='TRUE';
      NO_DIR_CHECK='TRUE';
      ALLOW_CONNECT='TRUE';
    'VPLLAV331':
      PIN_NUMBER='(0,0,0,0,0,0,H7)';
      PINUSE='POWER';
      NO_LOAD_CHECK='Both';
      NO_IO_CHECK='Both';
      NO_ASSERT_CHECK='TRUE';
      NO_DIR_CHECK='TRUE';
      ALLOW_CONNECT='TRUE';
    'PEAV33':
      PIN_NUMBER='(0,0,0,0,0,0,L16)';
      PINUSE='POWER';
      NO_LOAD_CHECK='Both';
      NO_IO_CHECK='Both';
      NO_ASSERT_CHECK='TRUE';
      NO_DIR_CHECK='TRUE';
      ALLOW_CONNECT='TRUE';
    'BATVDD':
      PIN_NUMBER='(0,0,0,0,0,0,E4)';
      PINUSE='POWER';
      NO_LOAD_CHECK='Both';
      NO_IO_CHECK='Both';
      NO_ASSERT_CHECK='TRUE';
      NO_DIR_CHECK='TRUE';
      ALLOW_CONNECT='TRUE';
    'USB2AV33':
      PIN_NUMBER='(0,0,0,0,0,0,C7)';
      PINUSE='POWER';
      NO_LOAD_CHECK='Both';
      NO_IO_CHECK='Both';
      NO_ASSERT_CHECK='TRUE';
      NO_DIR_CHECK='TRUE';
      ALLOW_CONNECT='TRUE';
    'DACDV33':
      PIN_NUMBER='(0,0,0,0,0,0,K5)';
      PINUSE='POWER';
      NO_LOAD_CHECK='Both';
      NO_IO_CHECK='Both';
      NO_ASSERT_CHECK='TRUE';
      NO_DIR_CHECK='TRUE';
      ALLOW_CONNECT='TRUE';
    'ADCAV33':
      PIN_NUMBER='(0,0,0,0,0,0,J6)';
      PINUSE='POWER';
      NO_LOAD_CHECK='Both';
      NO_IO_CHECK='Both';
      NO_ASSERT_CHECK='TRUE';
      NO_DIR_CHECK='TRUE';
      ALLOW_CONNECT='TRUE';
    'R2VDD0':
      PIN_NUMBER='(0,0,0,0,0,0,F7)';
      PINUSE='POWER';
      NO_LOAD_CHECK='Both';
      NO_IO_CHECK='Both';
      NO_ASSERT_CHECK='TRUE';
      NO_DIR_CHECK='TRUE';
      ALLOW_CONNECT='TRUE';
    'R2VDD1':
      PIN_NUMBER='(0,0,0,0,0,0,F8)';
      PINUSE='POWER';
      NO_LOAD_CHECK='Both';
      NO_IO_CHECK='Both';
      NO_ASSERT_CHECK='TRUE';
      NO_DIR_CHECK='TRUE';
      ALLOW_CONNECT='TRUE';
    'R1VDD0':
      PIN_NUMBER='(0,0,0,0,0,0,F10)';
      PINUSE='POWER';
      NO_LOAD_CHECK='Both';
      NO_IO_CHECK='Both';
      NO_ASSERT_CHECK='TRUE';
      NO_DIR_CHECK='TRUE';
      ALLOW_CONNECT='TRUE';
    'R1VDD1':
      PIN_NUMBER='(0,0,0,0,0,0,F11)';
      PINUSE='POWER';
      NO_LOAD_CHECK='Both';
      NO_IO_CHECK='Both';
      NO_ASSERT_CHECK='TRUE';
      NO_DIR_CHECK='TRUE';
      ALLOW_CONNECT='TRUE';
    'GND67':
      PIN_NUMBER='(0,0,0,0,0,0,V8)';
      PINUSE='POWER';
      NO_LOAD_CHECK='Both';
      NO_IO_CHECK='Both';
      NO_ASSERT_CHECK='TRUE';
      NO_DIR_CHECK='TRUE';
      ALLOW_CONNECT='TRUE';
    'GND66':
      PIN_NUMBER='(0,0,0,0,0,0,V16)';
      PINUSE='POWER';
      NO_LOAD_CHECK='Both';
      NO_IO_CHECK='Both';
      NO_ASSERT_CHECK='TRUE';
      NO_DIR_CHECK='TRUE';
      ALLOW_CONNECT='TRUE';
    'GND65':
      PIN_NUMBER='(0,0,0,0,0,0,V14)';
      PINUSE='POWER';
      NO_LOAD_CHECK='Both';
      NO_IO_CHECK='Both';
      NO_ASSERT_CHECK='TRUE';
      NO_DIR_CHECK='TRUE';
      ALLOW_CONNECT='TRUE';
    'GND60':
      PIN_NUMBER='(0,0,0,0,0,0,T7)';
      PINUSE='POWER';
      NO_LOAD_CHECK='Both';
      NO_IO_CHECK='Both';
      NO_ASSERT_CHECK='TRUE';
      NO_DIR_CHECK='TRUE';
      ALLOW_CONNECT='TRUE';
    'GND61':
      PIN_NUMBER='(0,0,0,0,0,0,U11)';
      PINUSE='POWER';
      NO_LOAD_CHECK='Both';
      NO_IO_CHECK='Both';
      NO_ASSERT_CHECK='TRUE';
      NO_DIR_CHECK='TRUE';
      ALLOW_CONNECT='TRUE';
    'GND64':
      PIN_NUMBER='(0,0,0,0,0,0,V12)';
      PINUSE='POWER';
      NO_LOAD_CHECK='Both';
      NO_IO_CHECK='Both';
      NO_ASSERT_CHECK='TRUE';
      NO_DIR_CHECK='TRUE';
      ALLOW_CONNECT='TRUE';
    'GND63':
      PIN_NUMBER='(0,0,0,0,0,0,V10)';
      PINUSE='POWER';
      NO_LOAD_CHECK='Both';
      NO_IO_CHECK='Both';
      NO_ASSERT_CHECK='TRUE';
      NO_DIR_CHECK='TRUE';
      ALLOW_CONNECT='TRUE';
    'GND62':
      PIN_NUMBER='(0,0,0,0,0,0,U6)';
      PINUSE='POWER';
      NO_LOAD_CHECK='Both';
      NO_IO_CHECK='Both';
      NO_ASSERT_CHECK='TRUE';
      NO_DIR_CHECK='TRUE';
      ALLOW_CONNECT='TRUE';
    'GND55':
      PIN_NUMBER='(0,0,0,0,0,0,N13)';
      PINUSE='POWER';
      NO_LOAD_CHECK='Both';
      NO_IO_CHECK='Both';
      NO_ASSERT_CHECK='TRUE';
      NO_DIR_CHECK='TRUE';
      ALLOW_CONNECT='TRUE';
    'GND56':
      PIN_NUMBER='(0,0,0,0,0,0,N14)';
      PINUSE='POWER';
      NO_LOAD_CHECK='Both';
      NO_IO_CHECK='Both';
      NO_ASSERT_CHECK='TRUE';
      NO_DIR_CHECK='TRUE';
      ALLOW_CONNECT='TRUE';
    'GND59':
      PIN_NUMBER='(0,0,0,0,0,0,T6)';
      PINUSE='POWER';
      NO_LOAD_CHECK='Both';
      NO_IO_CHECK='Both';
      NO_ASSERT_CHECK='TRUE';
      NO_DIR_CHECK='TRUE';
      ALLOW_CONNECT='TRUE';
    'GND58':
      PIN_NUMBER='(0,0,0,0,0,0,T16)';
      PINUSE='POWER';
      NO_LOAD_CHECK='Both';
      NO_IO_CHECK='Both';
      NO_ASSERT_CHECK='TRUE';
      NO_DIR_CHECK='TRUE';
      ALLOW_CONNECT='TRUE';
    'GND57':
      PIN_NUMBER='(0,0,0,0,0,0,N9)';
      PINUSE='POWER';
      NO_LOAD_CHECK='Both';
      NO_IO_CHECK='Both';
      NO_ASSERT_CHECK='TRUE';
      NO_DIR_CHECK='TRUE';
      ALLOW_CONNECT='TRUE';
    'GND50':
      PIN_NUMBER='(0,0,0,0,0,0,M7)';
      PINUSE='POWER';
      NO_LOAD_CHECK='Both';
      NO_IO_CHECK='Both';
      NO_ASSERT_CHECK='TRUE';
      NO_DIR_CHECK='TRUE';
      ALLOW_CONNECT='TRUE';
    'GND51':
      PIN_NUMBER='(0,0,0,0,0,0,M9)';
      PINUSE='POWER';
      NO_LOAD_CHECK='Both';
      NO_IO_CHECK='Both';
      NO_ASSERT_CHECK='TRUE';
      NO_DIR_CHECK='TRUE';
      ALLOW_CONNECT='TRUE';
    'GND54':
      PIN_NUMBER='(0,0,0,0,0,0,N12)';
      PINUSE='POWER';
      NO_LOAD_CHECK='Both';
      NO_IO_CHECK='Both';
      NO_ASSERT_CHECK='TRUE';
      NO_DIR_CHECK='TRUE';
      ALLOW_CONNECT='TRUE';
    'GND53':
      PIN_NUMBER='(0,0,0,0,0,0,N11)';
      PINUSE='POWER';
      NO_LOAD_CHECK='Both';
      NO_IO_CHECK='Both';
      NO_ASSERT_CHECK='TRUE';
      NO_DIR_CHECK='TRUE';
      ALLOW_CONNECT='TRUE';
    'GND52':
      PIN_NUMBER='(0,0,0,0,0,0,N10)';
      PINUSE='POWER';
      NO_LOAD_CHECK='Both';
      NO_IO_CHECK='Both';
      NO_ASSERT_CHECK='TRUE';
      NO_DIR_CHECK='TRUE';
      ALLOW_CONNECT='TRUE';
    'GND45':
      PIN_NUMBER='(0,0,0,0,0,0,M2)';
      PINUSE='POWER';
      NO_LOAD_CHECK='Both';
      NO_IO_CHECK='Both';
      NO_ASSERT_CHECK='TRUE';
      NO_DIR_CHECK='TRUE';
      ALLOW_CONNECT='TRUE';
    'GND46':
      PIN_NUMBER='(0,0,0,0,0,0,M3)';
      PINUSE='POWER';
      NO_LOAD_CHECK='Both';
      NO_IO_CHECK='Both';
      NO_ASSERT_CHECK='TRUE';
      NO_DIR_CHECK='TRUE';
      ALLOW_CONNECT='TRUE';
    'GND49':
      PIN_NUMBER='(0,0,0,0,0,0,M6)';
      PINUSE='POWER';
      NO_LOAD_CHECK='Both';
      NO_IO_CHECK='Both';
      NO_ASSERT_CHECK='TRUE';
      NO_DIR_CHECK='TRUE';
      ALLOW_CONNECT='TRUE';
    'GND48':
      PIN_NUMBER='(0,0,0,0,0,0,M5)';
      PINUSE='POWER';
      NO_LOAD_CHECK='Both';
      NO_IO_CHECK='Both';
      NO_ASSERT_CHECK='TRUE';
      NO_DIR_CHECK='TRUE';
      ALLOW_CONNECT='TRUE';
    'GND47':
      PIN_NUMBER='(0,0,0,0,0,0,M4)';
      PINUSE='POWER';
      NO_LOAD_CHECK='Both';
      NO_IO_CHECK='Both';
      NO_ASSERT_CHECK='TRUE';
      NO_DIR_CHECK='TRUE';
      ALLOW_CONNECT='TRUE';
    'GND40':
      PIN_NUMBER='(0,0,0,0,0,0,M12)';
      PINUSE='POWER';
      NO_LOAD_CHECK='Both';
      NO_IO_CHECK='Both';
      NO_ASSERT_CHECK='TRUE';
      NO_DIR_CHECK='TRUE';
      ALLOW_CONNECT='TRUE';
    'GND41':
      PIN_NUMBER='(0,0,0,0,0,0,M13)';
      PINUSE='POWER';
      NO_LOAD_CHECK='Both';
      NO_IO_CHECK='Both';
      NO_ASSERT_CHECK='TRUE';
      NO_DIR_CHECK='TRUE';
      ALLOW_CONNECT='TRUE';
    'GND44':
      PIN_NUMBER='(0,0,0,0,0,0,M17)';
      PINUSE='POWER';
      NO_LOAD_CHECK='Both';
      NO_IO_CHECK='Both';
      NO_ASSERT_CHECK='TRUE';
      NO_DIR_CHECK='TRUE';
      ALLOW_CONNECT='TRUE';
    'GND43':
      PIN_NUMBER='(0,0,0,0,0,0,M16)';
      PINUSE='POWER';
      NO_LOAD_CHECK='Both';
      NO_IO_CHECK='Both';
      NO_ASSERT_CHECK='TRUE';
      NO_DIR_CHECK='TRUE';
      ALLOW_CONNECT='TRUE';
    'GND42':
      PIN_NUMBER='(0,0,0,0,0,0,M14)';
      PINUSE='POWER';
      NO_LOAD_CHECK='Both';
      NO_IO_CHECK='Both';
      NO_ASSERT_CHECK='TRUE';
      NO_DIR_CHECK='TRUE';
      ALLOW_CONNECT='TRUE';
    'GND35':
      PIN_NUMBER='(0,0,0,0,0,0,L14)';
      PINUSE='POWER';
      NO_LOAD_CHECK='Both';
      NO_IO_CHECK='Both';
      NO_ASSERT_CHECK='TRUE';
      NO_DIR_CHECK='TRUE';
      ALLOW_CONNECT='TRUE';
    'GND39':
      PIN_NUMBER='(0,0,0,0,0,0,M11)';
      PINUSE='POWER';
      NO_LOAD_CHECK='Both';
      NO_IO_CHECK='Both';
      NO_ASSERT_CHECK='TRUE';
      NO_DIR_CHECK='TRUE';
      ALLOW_CONNECT='TRUE';
    'GND38':
      PIN_NUMBER='(0,0,0,0,0,0,M10)';
      PINUSE='POWER';
      NO_LOAD_CHECK='Both';
      NO_IO_CHECK='Both';
      NO_ASSERT_CHECK='TRUE';
      NO_DIR_CHECK='TRUE';
      ALLOW_CONNECT='TRUE';
    'GND37':
      PIN_NUMBER='(0,0,0,0,0,0,M1)';
      PINUSE='POWER';
      NO_LOAD_CHECK='Both';
      NO_IO_CHECK='Both';
      NO_ASSERT_CHECK='TRUE';
      NO_DIR_CHECK='TRUE';
      ALLOW_CONNECT='TRUE';
    'GND36':
      PIN_NUMBER='(0,0,0,0,0,0,L9)';
      PINUSE='POWER';
      NO_LOAD_CHECK='Both';
      NO_IO_CHECK='Both';
      NO_ASSERT_CHECK='TRUE';
      NO_DIR_CHECK='TRUE';
      ALLOW_CONNECT='TRUE';
    'GND30':
      PIN_NUMBER='(0,0,0,0,0,0,K9)';
      PINUSE='POWER';
      NO_LOAD_CHECK='Both';
      NO_IO_CHECK='Both';
      NO_ASSERT_CHECK='TRUE';
      NO_DIR_CHECK='TRUE';
      ALLOW_CONNECT='TRUE';
    'GND34':
      PIN_NUMBER='(0,0,0,0,0,0,L13)';
      PINUSE='POWER';
      NO_LOAD_CHECK='Both';
      NO_IO_CHECK='Both';
      NO_ASSERT_CHECK='TRUE';
      NO_DIR_CHECK='TRUE';
      ALLOW_CONNECT='TRUE';
    'GND33':
      PIN_NUMBER='(0,0,0,0,0,0,L12)';
      PINUSE='POWER';
      NO_LOAD_CHECK='Both';
      NO_IO_CHECK='Both';
      NO_ASSERT_CHECK='TRUE';
      NO_DIR_CHECK='TRUE';
      ALLOW_CONNECT='TRUE';
    'GND32':
      PIN_NUMBER='(0,0,0,0,0,0,L11)';
      PINUSE='POWER';
      NO_LOAD_CHECK='Both';
      NO_IO_CHECK='Both';
      NO_ASSERT_CHECK='TRUE';
      NO_DIR_CHECK='TRUE';
      ALLOW_CONNECT='TRUE';
    'GND31':
      PIN_NUMBER='(0,0,0,0,0,0,L10)';
      PINUSE='POWER';
      NO_LOAD_CHECK='Both';
      NO_IO_CHECK='Both';
      NO_ASSERT_CHECK='TRUE';
      NO_DIR_CHECK='TRUE';
      ALLOW_CONNECT='TRUE';
    'GND29':
      PIN_NUMBER='(0,0,0,0,0,0,K16)';
      PINUSE='POWER';
      NO_LOAD_CHECK='Both';
      NO_IO_CHECK='Both';
      NO_ASSERT_CHECK='TRUE';
      NO_DIR_CHECK='TRUE';
      ALLOW_CONNECT='TRUE';
    'GND25':
      PIN_NUMBER='(0,0,0,0,0,0,K11)';
      PINUSE='POWER';
      NO_LOAD_CHECK='Both';
      NO_IO_CHECK='Both';
      NO_ASSERT_CHECK='TRUE';
      NO_DIR_CHECK='TRUE';
      ALLOW_CONNECT='TRUE';
    'GND27':
      PIN_NUMBER='(0,0,0,0,0,0,K13)';
      PINUSE='POWER';
      NO_LOAD_CHECK='Both';
      NO_IO_CHECK='Both';
      NO_ASSERT_CHECK='TRUE';
      NO_DIR_CHECK='TRUE';
      ALLOW_CONNECT='TRUE';
    'GND28':
      PIN_NUMBER='(0,0,0,0,0,0,K14)';
      PINUSE='POWER';
      NO_LOAD_CHECK='Both';
      NO_IO_CHECK='Both';
      NO_ASSERT_CHECK='TRUE';
      NO_DIR_CHECK='TRUE';
      ALLOW_CONNECT='TRUE';
    'GND26':
      PIN_NUMBER='(0,0,0,0,0,0,K12)';
      PINUSE='POWER';
      NO_LOAD_CHECK='Both';
      NO_IO_CHECK='Both';
      NO_ASSERT_CHECK='TRUE';
      NO_DIR_CHECK='TRUE';
      ALLOW_CONNECT='TRUE';
    'GND24':
      PIN_NUMBER='(0,0,0,0,0,0,K10)';
      PINUSE='POWER';
      NO_LOAD_CHECK='Both';
      NO_IO_CHECK='Both';
      NO_ASSERT_CHECK='TRUE';
      NO_DIR_CHECK='TRUE';
      ALLOW_CONNECT='TRUE';
    'GND20':
      PIN_NUMBER='(0,0,0,0,0,0,J21)';
      PINUSE='POWER';
      NO_LOAD_CHECK='Both';
      NO_IO_CHECK='Both';
      NO_ASSERT_CHECK='TRUE';
      NO_DIR_CHECK='TRUE';
      ALLOW_CONNECT='TRUE';
    'GND23':
      PIN_NUMBER='(0,0,0,0,0,0,J9)';
      PINUSE='POWER';
      NO_LOAD_CHECK='Both';
      NO_IO_CHECK='Both';
      NO_ASSERT_CHECK='TRUE';
      NO_DIR_CHECK='TRUE';
      ALLOW_CONNECT='TRUE';
    'GND22':
      PIN_NUMBER='(0,0,0,0,0,0,J5)';
      PINUSE='POWER';
      NO_LOAD_CHECK='Both';
      NO_IO_CHECK='Both';
      NO_ASSERT_CHECK='TRUE';
      NO_DIR_CHECK='TRUE';
      ALLOW_CONNECT='TRUE';
    'GND21':
      PIN_NUMBER='(0,0,0,0,0,0,J22)';
      PINUSE='POWER';
      NO_LOAD_CHECK='Both';
      NO_IO_CHECK='Both';
      NO_ASSERT_CHECK='TRUE';
      NO_DIR_CHECK='TRUE';
      ALLOW_CONNECT='TRUE';
    'GND19':
      PIN_NUMBER='(0,0,0,0,0,0,J14)';
      PINUSE='POWER';
      NO_LOAD_CHECK='Both';
      NO_IO_CHECK='Both';
      NO_ASSERT_CHECK='TRUE';
      NO_DIR_CHECK='TRUE';
      ALLOW_CONNECT='TRUE';
    'GND14':
      PIN_NUMBER='(0,0,0,0,0,0,H6)';
      PINUSE='POWER';
      NO_LOAD_CHECK='Both';
      NO_IO_CHECK='Both';
      NO_ASSERT_CHECK='TRUE';
      NO_DIR_CHECK='TRUE';
      ALLOW_CONNECT='TRUE';
    'GND15':
      PIN_NUMBER='(0,0,0,0,0,0,J10)';
      PINUSE='POWER';
      NO_LOAD_CHECK='Both';
      NO_IO_CHECK='Both';
      NO_ASSERT_CHECK='TRUE';
      NO_DIR_CHECK='TRUE';
      ALLOW_CONNECT='TRUE';
    'GND18':
      PIN_NUMBER='(0,0,0,0,0,0,J13)';
      PINUSE='POWER';
      NO_LOAD_CHECK='Both';
      NO_IO_CHECK='Both';
      NO_ASSERT_CHECK='TRUE';
      NO_DIR_CHECK='TRUE';
      ALLOW_CONNECT='TRUE';
    'GND17':
      PIN_NUMBER='(0,0,0,0,0,0,J12)';
      PINUSE='POWER';
      NO_LOAD_CHECK='Both';
      NO_IO_CHECK='Both';
      NO_ASSERT_CHECK='TRUE';
      NO_DIR_CHECK='TRUE';
      ALLOW_CONNECT='TRUE';
    'GND16':
      PIN_NUMBER='(0,0,0,0,0,0,J11)';
      PINUSE='POWER';
      NO_LOAD_CHECK='Both';
      NO_IO_CHECK='Both';
      NO_ASSERT_CHECK='TRUE';
      NO_DIR_CHECK='TRUE';
      ALLOW_CONNECT='TRUE';
    'GND9':
      PIN_NUMBER='(0,0,0,0,0,0,C6)';
      PINUSE='POWER';
      NO_LOAD_CHECK='Both';
      NO_IO_CHECK='Both';
      NO_ASSERT_CHECK='TRUE';
      NO_DIR_CHECK='TRUE';
      ALLOW_CONNECT='TRUE';
    'GND10':
      PIN_NUMBER='(0,0,0,0,0,0,E8)';
      PINUSE='POWER';
      NO_LOAD_CHECK='Both';
      NO_IO_CHECK='Both';
      NO_ASSERT_CHECK='TRUE';
      NO_DIR_CHECK='TRUE';
      ALLOW_CONNECT='TRUE';
    'GND13':
      PIN_NUMBER='(0,0,0,0,0,0,G6)';
      PINUSE='POWER';
      NO_LOAD_CHECK='Both';
      NO_IO_CHECK='Both';
      NO_ASSERT_CHECK='TRUE';
      NO_DIR_CHECK='TRUE';
      ALLOW_CONNECT='TRUE';
    'GND12':
      PIN_NUMBER='(0,0,0,0,0,0,G19)';
      PINUSE='POWER';
      NO_LOAD_CHECK='Both';
      NO_IO_CHECK='Both';
      NO_ASSERT_CHECK='TRUE';
      NO_DIR_CHECK='TRUE';
      ALLOW_CONNECT='TRUE';
    'GND11':
      PIN_NUMBER='(0,0,0,0,0,0,F16)';
      PINUSE='POWER';
      NO_LOAD_CHECK='Both';
      NO_IO_CHECK='Both';
      NO_ASSERT_CHECK='TRUE';
      NO_DIR_CHECK='TRUE';
      ALLOW_CONNECT='TRUE';
    'GND4':
      PIN_NUMBER='(0,0,0,0,0,0,AA15)';
      PINUSE='POWER';
      NO_LOAD_CHECK='Both';
      NO_IO_CHECK='Both';
      NO_ASSERT_CHECK='TRUE';
      NO_DIR_CHECK='TRUE';
      ALLOW_CONNECT='TRUE';
    'GND5':
      PIN_NUMBER='(0,0,0,0,0,0,AA7)';
      PINUSE='POWER';
      NO_LOAD_CHECK='Both';
      NO_IO_CHECK='Both';
      NO_ASSERT_CHECK='TRUE';
      NO_DIR_CHECK='TRUE';
      ALLOW_CONNECT='TRUE';
    'GND7':
      PIN_NUMBER='(0,0,0,0,0,0,AB1)';
      PINUSE='POWER';
      NO_LOAD_CHECK='Both';
      NO_IO_CHECK='Both';
      NO_ASSERT_CHECK='TRUE';
      NO_DIR_CHECK='TRUE';
      ALLOW_CONNECT='TRUE';
    'GND8':
      PIN_NUMBER='(0,0,0,0,0,0,AB22)';
      PINUSE='POWER';
      NO_LOAD_CHECK='Both';
      NO_IO_CHECK='Both';
      NO_ASSERT_CHECK='TRUE';
      NO_DIR_CHECK='TRUE';
      ALLOW_CONNECT='TRUE';
    'GND6':
      PIN_NUMBER='(0,0,0,0,0,0,AA9)';
      PINUSE='POWER';
      NO_LOAD_CHECK='Both';
      NO_IO_CHECK='Both';
      NO_ASSERT_CHECK='TRUE';
      NO_DIR_CHECK='TRUE';
      ALLOW_CONNECT='TRUE';
    'GND3':
      PIN_NUMBER='(0,0,0,0,0,0,AA13)';
      PINUSE='POWER';
      NO_LOAD_CHECK='Both';
      NO_IO_CHECK='Both';
      NO_ASSERT_CHECK='TRUE';
      NO_DIR_CHECK='TRUE';
      ALLOW_CONNECT='TRUE';
    'GND2':
      PIN_NUMBER='(0,0,0,0,0,0,AA11)';
      PINUSE='POWER';
      NO_LOAD_CHECK='Both';
      NO_IO_CHECK='Both';
      NO_ASSERT_CHECK='TRUE';
      NO_DIR_CHECK='TRUE';
      ALLOW_CONNECT='TRUE';
    'GND1':
      PIN_NUMBER='(0,0,0,0,0,0,A22)';
      PINUSE='POWER';
      NO_LOAD_CHECK='Both';
      NO_IO_CHECK='Both';
      NO_ASSERT_CHECK='TRUE';
      NO_DIR_CHECK='TRUE';
      ALLOW_CONNECT='TRUE';
    'GND0':
      PIN_NUMBER='(0,0,0,0,0,0,A1)';
      PINUSE='POWER';
      NO_LOAD_CHECK='Both';
      NO_IO_CHECK='Both';
      NO_ASSERT_CHECK='TRUE';
      NO_DIR_CHECK='TRUE';
      ALLOW_CONNECT='TRUE';
  end_pin;
  body
    PART_NAME='AST2520A1-GP-GP';
    BODY_NAME='AST2520A1-GP-GP';
    PHYS_DES_PREFIX='U';
    CLASS='IC';
  end_body;
end_primitive;

END.
